FILE_TYPE = MACRO_DRAWING;
SET COLOR_WIRE YELLOW;
SET COLOR_PROP ORANGE;
SET COLOR_DOT WHITE;
SET COLOR_ARC YELLOW;
SET COLOR_BODY GREEN;
SET COLOR_NOTE PURPLE;
SET PROP_DISPLAY VALUE;
SET PAGE_NUMBER P164;
FORCEADD GND_SG..1
(-11000 -1050);
FORCEPROP 3 LASTPIN (-10950 -1000) SIG_NAME SG\g
J 0
(-10940 -990);
DISPLAY 0.659574 (-10940 -990);
PAINT MONO (-10940 -990);
DISPLAY INVISIBLE (-10940 -990);
FORCEPROP 1 LAST HDL_POWER SG
J 1
(-10950 -1150);
DISPLAY 0.808511 (-10950 -1150);
PAINT GREEN (-10950 -1150);
FORCEPROP 1 LAST PATH I1
J 0
(-10965 -1050);
DISPLAY 0.808511 (-10965 -1050);
PAINT GREEN (-10965 -1050);
DISPLAY INVISIBLE (-10965 -1050);
FORCEPROP 1 LAST BODY_TYPE PLUMBING
J 0
(-10985 -1065);
DISPLAY 0.808511 (-10985 -1065);
PAINT GREEN (-10985 -1065);
DISPLAY INVISIBLE (-10985 -1065);
FORCEPROP 2 LAST CDS_LIB cls
J 0
(-11000 -1050);
DISPLAY INVISIBLE (-11000 -1050);
FORCEPROP 1 LAST CDS_LMAN_SYM_OUTLINE 0,0,100,-50
J 0
(-11000 -1050);
DISPLAY 0.468085 (-11000 -1050);
PAINT GREEN (-11000 -1050);
DISPLAY INVISIBLE (-11000 -1050);
FORCEADD FERRITEBEAD..1
(-7500 7450);
FORCEPROP 0 LAST PACKAGE 0603
J 0
(-7500 7500);
DISPLAY 1.021277 (-7500 7500);
FORCEPROP 1 LAST VALUE 120OHM
J 0
(-7250 7500);
DISPLAY 1.212766 (-7250 7500);
PAINT GREEN (-7250 7500);
FORCEPROP 1 LAST TOLERANCE 25%
J 0
(-7600 7500);
DISPLAY 1.212766 (-7600 7500);
PAINT GREEN (-7600 7500);
DISPLAY INVISIBLE (-7600 7500);
FORCEPROP 1 LAST PATH I102
J 2
(-7550 7500);
DISPLAY 1.212766 (-7550 7500);
PAINT GREEN (-7550 7500);
DISPLAY INVISIBLE (-7550 7500);
FORCEPROP 1 LAST CDS_LMAN_SYM_OUTLINE 0,0,200,-100
J 0
(-7500 7450);
DISPLAY 0.468085 (-7500 7450);
PAINT GREEN (-7500 7450);
DISPLAY INVISIBLE (-7500 7450);
FORCEPROP 2 LAST CDS_LIB passive
J 0
(-7500 7450);
DISPLAY INVISIBLE (-7500 7450);
FORCEPROP 1 LAST CLS_PN G191-10100-01
J 2
(-7550 7500);
DISPLAY 1.212766 (-7550 7500);
PAINT GREEN (-7550 7500);
DISPLAY INVISIBLE (-7550 7500);
FORCEPROP 1 LAST $LOCATION L33
J 2
(-7550 7500);
DISPLAY 1.212766 (-7550 7500);
PAINT GREEN (-7550 7500);
FORCEPROP 0 LASTPIN (-7600 7400) $PN 1
J 2
(-7610 7410);
DISPLAY 0.680851 (-7610 7410);
PAINT MONO (-7610 7410);
FORCEPROP 0 LASTPIN (-7200 7400) $PN 2
J 0
(-7190 7410);
DISPLAY 0.680851 (-7190 7410);
PAINT MONO (-7190 7410);
FORCEPROP 0 LAST CDS_LOCATION L33
J 2
(-7550 7500);
DISPLAY 1.212766 (-7550 7500);
PAINT GREEN (-7550 7500);
DISPLAY INVISIBLE (-7550 7500);
FORCEPROP 0 LAST $SEC 1
J 0
(-7550 7600);
DISPLAY 0.680851 (-7550 7600);
PAINT MONO (-7550 7600);
DISPLAY INVISIBLE (-7550 7600);
FORCEPROP 0 LAST CDS_SEC 1
J 0
(-7550 7600);
DISPLAY 1.021277 (-7550 7600);
DISPLAY INVISIBLE (-7550 7600);
FORCEADD GND_SG..1
(-11000 3100);
FORCEPROP 3 LASTPIN (-10950 3150) SIG_NAME SG\g
J 0
(-10940 3160);
DISPLAY 0.659574 (-10940 3160);
PAINT MONO (-10940 3160);
DISPLAY INVISIBLE (-10940 3160);
FORCEPROP 1 LAST HDL_POWER SG
J 1
(-10945 3005);
DISPLAY 0.808511 (-10945 3005);
PAINT GREEN (-10945 3005);
FORCEPROP 1 LAST PATH I134
J 0
(-10965 3100);
DISPLAY 0.808511 (-10965 3100);
PAINT GREEN (-10965 3100);
DISPLAY INVISIBLE (-10965 3100);
FORCEPROP 1 LAST BODY_TYPE PLUMBING
J 0
(-10985 3085);
DISPLAY 0.808511 (-10985 3085);
PAINT GREEN (-10985 3085);
DISPLAY INVISIBLE (-10985 3085);
FORCEPROP 1 LAST CDS_LMAN_SYM_OUTLINE 0,0,100,-50
J 0
(-11000 3100);
DISPLAY 0.468085 (-11000 3100);
PAINT GREEN (-11000 3100);
DISPLAY INVISIBLE (-11000 3100);
FORCEPROP 2 LAST CDS_LIB cls
J 0
(-11000 3100);
DISPLAY INVISIBLE (-11000 3100);
FORCEADD VCC..1
(-11250 -200);
FORCEPROP 3 LASTPIN (-11200 -250) SIG_NAME FPGA_MGTAVTT\g
J 0
(-11190 -240);
DISPLAY 0.659574 (-11190 -240);
PAINT MONO (-11190 -240);
DISPLAY INVISIBLE (-11190 -240);
FORCEPROP 1 LAST HDL_POWER FPGA_MGTAVTT
J 1
(-11195 -145);
DISPLAY 0.808511 (-11195 -145);
PAINT GREEN (-11195 -145);
FORCEPROP 0 LAST VOLTAGE 1.2
J 0
(-11400 -100);
DISPLAY 0.808511 (-11400 -100);
DISPLAY BOTH (-11400 -100);
FORCEPROP 1 LAST PATH I135
J 0
(-11215 -110);
DISPLAY 0.808511 (-11215 -110);
PAINT GREEN (-11215 -110);
DISPLAY INVISIBLE (-11215 -110);
FORCEPROP 1 LAST BODY_TYPE PLUMBING
J 0
(-11295 -243);
DISPLAY 0.340426 (-11295 -243);
PAINT GREEN (-11295 -243);
DISPLAY INVISIBLE (-11295 -243);
FORCEPROP 1 LAST CDS_LMAN_SYM_OUTLINE -250,250,250,-250
J 0
(-11250 -200);
DISPLAY 0.468085 (-11250 -200);
PAINT GREEN (-11250 -200);
DISPLAY INVISIBLE (-11250 -200);
FORCEPROP 2 LAST CDS_LIB cls
J 0
(-11250 -200);
DISPLAY INVISIBLE (-11250 -200);
FORCEADD GND_SG..1
(-14500 -950);
FORCEPROP 3 LASTPIN (-14450 -900) SIG_NAME SG\g
J 0
(-14440 -890);
DISPLAY 0.659574 (-14440 -890);
PAINT MONO (-14440 -890);
DISPLAY INVISIBLE (-14440 -890);
FORCEPROP 1 LAST HDL_POWER SG
J 1
(-14450 -1050);
DISPLAY 0.808511 (-14450 -1050);
PAINT GREEN (-14450 -1050);
FORCEPROP 1 LAST PATH I137
J 0
(-14465 -950);
DISPLAY 0.808511 (-14465 -950);
PAINT GREEN (-14465 -950);
DISPLAY INVISIBLE (-14465 -950);
FORCEPROP 1 LAST BODY_TYPE PLUMBING
J 0
(-14485 -965);
DISPLAY 0.808511 (-14485 -965);
PAINT GREEN (-14485 -965);
DISPLAY INVISIBLE (-14485 -965);
FORCEPROP 2 LAST CDS_LIB cls
J 0
(-14500 -950);
DISPLAY INVISIBLE (-14500 -950);
FORCEPROP 1 LAST CDS_LMAN_SYM_OUTLINE 0,0,100,-50
J 0
(-14500 -950);
DISPLAY 0.468085 (-14500 -950);
PAINT GREEN (-14500 -950);
DISPLAY INVISIBLE (-14500 -950);
FORCEADD XC7A200T_2FBG484C_FBG484..5
R 5
(-12950 8100);
FORCEPROP 1 LAST CLS_PN G240-10069-01
J 2
(-12950 8300);
DISPLAY 1.212766 (-12950 8300);
PAINT GREEN (-12950 8300);
FORCEPROP 1 LAST PATH I138
R 3
J 2
(-12900 8150);
DISPLAY 1.212766 (-12900 8150);
PAINT GREEN (-12900 8150);
DISPLAY INVISIBLE (-12900 8150);
FORCEPROP 2 LAST CDS_LIB pld
R 3
J 0
(-12950 8100);
DISPLAY INVISIBLE (-12950 8100);
FORCEPROP 1 LAST CDS_LMAN_SYM_OUTLINE 0,0,9000,-1100
R 3
J 0
(-12950 8100);
DISPLAY 0.468085 (-12950 8100);
PAINT GREEN (-12950 8100);
DISPLAY INVISIBLE (-12950 8100);
FORCEPROP 1 LAST $LOCATION U24
J 2
(-12950 8400);
DISPLAY 1.212766 (-12950 8400);
PAINT GREEN (-12950 8400);
FORCEPROP 0 LASTPIN (-14150 8000) $PN A11
J 2
(-14160 8010);
DISPLAY 0.680851 (-14160 8010);
PAINT MONO (-14160 8010);
FORCEPROP 0 LASTPIN (-14150 7900) $PN A12
J 2
(-14160 7910);
DISPLAY 0.680851 (-14160 7910);
PAINT MONO (-14160 7910);
FORCEPROP 0 LASTPIN (-14150 7800) $PN A2
J 2
(-14160 7810);
DISPLAY 0.680851 (-14160 7810);
PAINT MONO (-14160 7810);
FORCEPROP 0 LASTPIN (-14150 7700) $PN A22
J 2
(-14160 7710);
DISPLAY 0.680851 (-14160 7710);
PAINT MONO (-14160 7710);
FORCEPROP 0 LASTPIN (-14150 7600) $PN A3
J 2
(-14160 7610);
DISPLAY 0.680851 (-14160 7610);
PAINT MONO (-14160 7610);
FORCEPROP 0 LASTPIN (-14150 7500) $PN A5
J 2
(-14160 7510);
DISPLAY 0.680851 (-14160 7510);
PAINT MONO (-14160 7510);
FORCEPROP 0 LASTPIN (-14150 7400) $PN A7
J 2
(-14160 7410);
DISPLAY 0.680851 (-14160 7410);
PAINT MONO (-14160 7410);
FORCEPROP 0 LASTPIN (-14150 7300) $PN A9
J 2
(-14160 7310);
DISPLAY 0.680851 (-14160 7310);
PAINT MONO (-14160 7310);
FORCEPROP 0 LASTPIN (-14150 7200) $PN AA12
J 2
(-14160 7210);
DISPLAY 0.680851 (-14160 7210);
PAINT MONO (-14160 7210);
FORCEPROP 0 LASTPIN (-14150 7100) $PN AA2
J 2
(-14160 7110);
DISPLAY 0.680851 (-14160 7110);
PAINT MONO (-14160 7110);
FORCEPROP 0 LASTPIN (-14150 7000) $PN AA22
J 2
(-14160 7010);
DISPLAY 0.680851 (-14160 7010);
PAINT MONO (-14160 7010);
FORCEPROP 0 LASTPIN (-14150 6900) $PN AB19
J 2
(-14160 6910);
DISPLAY 0.680851 (-14160 6910);
PAINT MONO (-14160 6910);
FORCEPROP 0 LASTPIN (-14150 6800) $PN AB9
J 2
(-14160 6810);
DISPLAY 0.680851 (-14160 6810);
PAINT MONO (-14160 6810);
FORCEPROP 0 LASTPIN (-14150 6700) $PN B12
J 2
(-14160 6710);
DISPLAY 0.680851 (-14160 6710);
PAINT MONO (-14160 6710);
FORCEPROP 0 LASTPIN (-14150 6600) $PN B19
J 2
(-14160 6610);
DISPLAY 0.680851 (-14160 6610);
PAINT MONO (-14160 6610);
FORCEPROP 0 LASTPIN (-14150 6500) $PN B3
J 2
(-14160 6510);
DISPLAY 0.680851 (-14160 6510);
PAINT MONO (-14160 6510);
FORCEPROP 0 LASTPIN (-14150 6400) $PN C10
J 2
(-14160 6410);
DISPLAY 0.680851 (-14160 6410);
PAINT MONO (-14160 6410);
FORCEPROP 0 LASTPIN (-14150 6300) $PN C12
J 2
(-14160 6310);
DISPLAY 0.680851 (-14160 6310);
PAINT MONO (-14160 6310);
FORCEPROP 0 LASTPIN (-14150 6200) $PN C16
J 2
(-14160 6210);
DISPLAY 0.680851 (-14160 6210);
PAINT MONO (-14160 6210);
FORCEPROP 0 LASTPIN (-14150 6100) $PN C3
J 2
(-14160 6110);
DISPLAY 0.680851 (-14160 6110);
PAINT MONO (-14160 6110);
FORCEPROP 0 LASTPIN (-14150 6000) $PN C6
J 2
(-14160 6010);
DISPLAY 0.680851 (-14160 6010);
PAINT MONO (-14160 6010);
FORCEPROP 0 LASTPIN (-14150 5900) $PN D12
J 2
(-14160 5910);
DISPLAY 0.680851 (-14160 5910);
PAINT MONO (-14160 5910);
FORCEPROP 0 LASTPIN (-14150 5800) $PN D13
J 2
(-14160 5810);
DISPLAY 0.680851 (-14160 5810);
PAINT MONO (-14160 5810);
FORCEPROP 0 LASTPIN (-14150 5700) $PN D3
J 2
(-14160 5710);
DISPLAY 0.680851 (-14160 5710);
PAINT MONO (-14160 5710);
FORCEPROP 0 LASTPIN (-14150 5600) $PN D4
J 2
(-14160 5610);
DISPLAY 0.680851 (-14160 5610);
PAINT MONO (-14160 5610);
FORCEPROP 0 LASTPIN (-14150 5500) $PN D8
J 2
(-14160 5510);
DISPLAY 0.680851 (-14160 5510);
PAINT MONO (-14160 5510);
FORCEPROP 0 LASTPIN (-14150 5400) $PN E11
J 2
(-14160 5410);
DISPLAY 0.680851 (-14160 5410);
PAINT MONO (-14160 5410);
FORCEPROP 0 LASTPIN (-14150 5300) $PN E20
J 2
(-14160 5310);
DISPLAY 0.680851 (-14160 5310);
PAINT MONO (-14160 5310);
FORCEPROP 0 LASTPIN (-14150 5200) $PN E4
J 2
(-14160 5210);
DISPLAY 0.680851 (-14160 5210);
PAINT MONO (-14160 5210);
FORCEPROP 0 LASTPIN (-14150 5100) $PN E5
J 2
(-14160 5110);
DISPLAY 0.680851 (-14160 5110);
PAINT MONO (-14160 5110);
FORCEPROP 0 LASTPIN (-14150 5000) $PN E7
J 2
(-14160 5010);
DISPLAY 0.680851 (-14160 5010);
PAINT MONO (-14160 5010);
FORCEPROP 0 LASTPIN (-14150 4900) $PN E9
J 2
(-14160 4910);
DISPLAY 0.680851 (-14160 4910);
PAINT MONO (-14160 4910);
FORCEPROP 0 LASTPIN (-14150 4800) $PN F11
J 2
(-14160 4810);
DISPLAY 0.680851 (-14160 4810);
PAINT MONO (-14160 4810);
FORCEPROP 0 LASTPIN (-14150 4700) $PN F17
J 2
(-14160 4710);
DISPLAY 0.680851 (-14160 4710);
PAINT MONO (-14160 4710);
FORCEPROP 0 LASTPIN (-14150 4600) $PN F5
J 2
(-14160 4610);
DISPLAY 0.680851 (-14160 4610);
PAINT MONO (-14160 4610);
FORCEPROP 0 LASTPIN (-14150 4500) $PN G10
J 2
(-14160 4510);
DISPLAY 0.680851 (-14160 4510);
PAINT MONO (-14160 4510);
FORCEPROP 0 LASTPIN (-14150 4400) $PN G12
J 2
(-14160 4410);
DISPLAY 0.680851 (-14160 4410);
PAINT MONO (-14160 4410);
FORCEPROP 0 LASTPIN (-14150 4300) $PN G14
J 2
(-14160 4310);
DISPLAY 0.680851 (-14160 4310);
PAINT MONO (-14160 4310);
FORCEPROP 0 LASTPIN (-14150 4200) $PN G5
J 2
(-14160 4210);
DISPLAY 0.680851 (-14160 4210);
PAINT MONO (-14160 4210);
FORCEPROP 0 LASTPIN (-14150 4100) $PN G6
J 2
(-14160 4110);
DISPLAY 0.680851 (-14160 4110);
PAINT MONO (-14160 4110);
FORCEPROP 0 LASTPIN (-14150 4000) $PN G7
J 2
(-14160 4010);
DISPLAY 0.680851 (-14160 4010);
PAINT MONO (-14160 4010);
FORCEPROP 0 LASTPIN (-14150 3900) $PN G8
J 2
(-14160 3910);
DISPLAY 0.680851 (-14160 3910);
PAINT MONO (-14160 3910);
FORCEPROP 0 LASTPIN (-14150 3800) $PN G9
J 2
(-14160 3810);
DISPLAY 0.680851 (-14160 3810);
PAINT MONO (-14160 3810);
FORCEPROP 0 LASTPIN (-14150 3700) $PN H1
J 2
(-14160 3710);
DISPLAY 0.680851 (-14160 3710);
PAINT MONO (-14160 3710);
FORCEPROP 0 LASTPIN (-14150 3600) $PN H11
J 2
(-14160 3610);
DISPLAY 0.680851 (-14160 3610);
PAINT MONO (-14160 3610);
FORCEPROP 0 LASTPIN (-14150 3500) $PN H21
J 2
(-14160 3510);
DISPLAY 0.680851 (-14160 3510);
PAINT MONO (-14160 3510);
FORCEPROP 0 LASTPIN (-14150 3400) $PN H7
J 2
(-14160 3410);
DISPLAY 0.680851 (-14160 3410);
PAINT MONO (-14160 3410);
FORCEPROP 0 LASTPIN (-14150 3300) $PN H9
J 2
(-14160 3310);
DISPLAY 0.680851 (-14160 3310);
PAINT MONO (-14160 3310);
FORCEPROP 0 LASTPIN (-14150 3200) $PN J10
J 2
(-14160 3210);
DISPLAY 0.680851 (-14160 3210);
PAINT MONO (-14160 3210);
FORCEPROP 0 LASTPIN (-14150 3100) $PN J12
J 2
(-14160 3110);
DISPLAY 0.680851 (-14160 3110);
PAINT MONO (-14160 3110);
FORCEPROP 0 LASTPIN (-14150 3000) $PN J18
J 2
(-14160 3010);
DISPLAY 0.680851 (-14160 3010);
PAINT MONO (-14160 3010);
FORCEPROP 0 LASTPIN (-14150 2900) $PN J8
J 2
(-14160 2910);
DISPLAY 0.680851 (-14160 2910);
PAINT MONO (-14160 2910);
FORCEPROP 0 LASTPIN (-14150 2800) $PN K11
J 2
(-14160 2810);
DISPLAY 0.680851 (-14160 2810);
PAINT MONO (-14160 2810);
FORCEPROP 0 LASTPIN (-14150 2700) $PN K15
J 2
(-14160 2710);
DISPLAY 0.680851 (-14160 2710);
PAINT MONO (-14160 2710);
FORCEPROP 0 LASTPIN (-14150 2600) $PN K5
J 2
(-14160 2610);
DISPLAY 0.680851 (-14160 2610);
PAINT MONO (-14160 2610);
FORCEPROP 0 LASTPIN (-14150 2500) $PN K7
J 2
(-14160 2510);
DISPLAY 0.680851 (-14160 2510);
PAINT MONO (-14160 2510);
FORCEPROP 0 LASTPIN (-14150 2400) $PN L2
J 2
(-14160 2410);
DISPLAY 0.680851 (-14160 2410);
PAINT MONO (-14160 2410);
FORCEPROP 0 LASTPIN (-14150 2300) $PN L22
J 2
(-14160 2310);
DISPLAY 0.680851 (-14160 2310);
PAINT MONO (-14160 2310);
FORCEPROP 0 LASTPIN (-14150 2200) $PN L8
J 2
(-14160 2210);
DISPLAY 0.680851 (-14160 2210);
PAINT MONO (-14160 2210);
FORCEPROP 0 LASTPIN (-14150 2100) $PN M11
J 2
(-14160 2110);
DISPLAY 0.680851 (-14160 2110);
PAINT MONO (-14160 2110);
FORCEPROP 0 LASTPIN (-14150 2000) $PN M19
J 2
(-14160 2010);
DISPLAY 0.680851 (-14160 2010);
PAINT MONO (-14160 2010);
FORCEPROP 0 LASTPIN (-14150 1900) $PN M7
J 2
(-14160 1910);
DISPLAY 0.680851 (-14160 1910);
PAINT MONO (-14160 1910);
FORCEPROP 0 LASTPIN (-14150 1800) $PN N16
J 2
(-14160 1810);
DISPLAY 0.680851 (-14160 1810);
PAINT MONO (-14160 1810);
FORCEPROP 0 LASTPIN (-14150 1700) $PN N6
J 2
(-14160 1710);
DISPLAY 0.680851 (-14160 1710);
PAINT MONO (-14160 1710);
FORCEPROP 0 LASTPIN (-14150 1600) $PN N8
J 2
(-14160 1610);
DISPLAY 0.680851 (-14160 1610);
PAINT MONO (-14160 1610);
FORCEPROP 0 LASTPIN (-14150 1500) $PN P11
J 2
(-14160 1510);
DISPLAY 0.680851 (-14160 1510);
PAINT MONO (-14160 1510);
FORCEPROP 0 LASTPIN (-14150 1400) $PN P13
J 2
(-14160 1410);
DISPLAY 0.680851 (-14160 1410);
PAINT MONO (-14160 1410);
FORCEPROP 0 LASTPIN (-14150 1300) $PN P3
J 2
(-14160 1310);
DISPLAY 0.680851 (-14160 1310);
PAINT MONO (-14160 1310);
FORCEPROP 0 LASTPIN (-14150 1200) $PN P7
J 2
(-14160 1210);
DISPLAY 0.680851 (-14160 1210);
PAINT MONO (-14160 1210);
FORCEPROP 0 LASTPIN (-14150 1100) $PN P9
J 2
(-14160 1110);
DISPLAY 0.680851 (-14160 1110);
PAINT MONO (-14160 1110);
FORCEPROP 0 LASTPIN (-14150 1000) $PN R10
J 2
(-14160 1010);
DISPLAY 0.680851 (-14160 1010);
PAINT MONO (-14160 1010);
FORCEPROP 0 LASTPIN (-14150 900) $PN R12
J 2
(-14160 910);
DISPLAY 0.680851 (-14160 910);
PAINT MONO (-14160 910);
FORCEPROP 0 LASTPIN (-14150 800) $PN R20
J 2
(-14160 810);
DISPLAY 0.680851 (-14160 810);
PAINT MONO (-14160 810);
FORCEPROP 0 LASTPIN (-14150 700) $PN R8
J 2
(-14160 710);
DISPLAY 0.680851 (-14160 710);
PAINT MONO (-14160 710);
FORCEPROP 0 LASTPIN (-14150 600) $PN T11
J 2
(-14160 610);
DISPLAY 0.680851 (-14160 610);
PAINT MONO (-14160 610);
FORCEPROP 0 LASTPIN (-14150 500) $PN T17
J 2
(-14160 510);
DISPLAY 0.680851 (-14160 510);
PAINT MONO (-14160 510);
FORCEPROP 0 LASTPIN (-14150 400) $PN T7
J 2
(-14160 410);
DISPLAY 0.680851 (-14160 410);
PAINT MONO (-14160 410);
FORCEPROP 0 LASTPIN (-14150 300) $PN T9
J 2
(-14160 310);
DISPLAY 0.680851 (-14160 310);
PAINT MONO (-14160 310);
FORCEPROP 0 LASTPIN (-14150 200) $PN U14
J 2
(-14160 210);
DISPLAY 0.680851 (-14160 210);
PAINT MONO (-14160 210);
FORCEPROP 0 LASTPIN (-14150 100) $PN U4
J 2
(-14160 110);
DISPLAY 0.680851 (-14160 110);
PAINT MONO (-14160 110);
FORCEPROP 0 LASTPIN (-14150 0) $PN V1
J 2
(-14160 10);
DISPLAY 0.680851 (-14160 10);
PAINT MONO (-14160 10);
FORCEPROP 0 LASTPIN (-14150 -100) $PN V11
J 2
(-14160 -90);
DISPLAY 0.680851 (-14160 -90);
PAINT MONO (-14160 -90);
FORCEPROP 0 LASTPIN (-14150 -200) $PN V21
J 2
(-14160 -190);
DISPLAY 0.680851 (-14160 -190);
PAINT MONO (-14160 -190);
FORCEPROP 0 LASTPIN (-14150 -300) $PN W18
J 2
(-14160 -290);
DISPLAY 0.680851 (-14160 -290);
PAINT MONO (-14160 -290);
FORCEPROP 0 LASTPIN (-14150 -400) $PN W8
J 2
(-14160 -390);
DISPLAY 0.680851 (-14160 -390);
PAINT MONO (-14160 -390);
FORCEPROP 0 LASTPIN (-14150 -500) $PN Y15
J 2
(-14160 -490);
DISPLAY 0.680851 (-14160 -490);
PAINT MONO (-14160 -490);
FORCEPROP 0 LASTPIN (-14150 -600) $PN Y5
J 2
(-14160 -590);
DISPLAY 0.680851 (-14160 -590);
PAINT MONO (-14160 -590);
FORCEPROP 0 LASTPIN (-14150 -800) $PN K9
J 2
(-14160 -790);
DISPLAY 0.680851 (-14160 -790);
PAINT MONO (-14160 -790);
FORCEPROP 0 LASTPIN (-12850 700) $PN D10
J 0
(-12840 710);
DISPLAY 0.680851 (-12840 710);
PAINT MONO (-12840 710);
FORCEPROP 0 LASTPIN (-12850 600) $PN D6
J 0
(-12840 610);
DISPLAY 0.680851 (-12840 610);
PAINT MONO (-12840 610);
FORCEPROP 0 LASTPIN (-12850 500) $PN E8
J 0
(-12840 510);
DISPLAY 0.680851 (-12840 510);
PAINT MONO (-12840 510);
FORCEPROP 0 LASTPIN (-12850 400) $PN F7
J 0
(-12840 410);
DISPLAY 0.680851 (-12840 410);
PAINT MONO (-12840 410);
FORCEPROP 0 LASTPIN (-12850 300) $PN F9
J 0
(-12840 310);
DISPLAY 0.680851 (-12840 310);
PAINT MONO (-12840 310);
FORCEPROP 0 LASTPIN (-12850 100) $PN B11
J 0
(-12840 110);
DISPLAY 0.680851 (-12840 110);
PAINT MONO (-12840 110);
FORCEPROP 0 LASTPIN (-12850 0) $PN B5
J 0
(-12840 10);
DISPLAY 0.680851 (-12840 10);
PAINT MONO (-12840 10);
FORCEPROP 0 LASTPIN (-12850 -100) $PN B7
J 0
(-12840 -90);
DISPLAY 0.680851 (-12840 -90);
PAINT MONO (-12840 -90);
FORCEPROP 0 LASTPIN (-12850 -200) $PN B9
J 0
(-12840 -190);
DISPLAY 0.680851 (-12840 -190);
PAINT MONO (-12840 -190);
FORCEPROP 0 LASTPIN (-12850 -300) $PN C4
J 0
(-12840 -290);
DISPLAY 0.680851 (-12840 -290);
PAINT MONO (-12840 -290);
FORCEPROP 0 LASTPIN (-12850 -400) $PN C8
J 0
(-12840 -390);
DISPLAY 0.680851 (-12840 -390);
PAINT MONO (-12840 -390);
FORCEPROP 0 LASTPIN (-12850 8000) $PN K10
J 0
(-12840 8010);
DISPLAY 0.680851 (-12840 8010);
PAINT MONO (-12840 8010);
FORCEPROP 0 LASTPIN (-12850 7900) $PN H12
J 0
(-12840 7910);
DISPLAY 0.680851 (-12840 7910);
PAINT MONO (-12840 7910);
FORCEPROP 0 LASTPIN (-12850 7800) $PN K12
J 0
(-12840 7810);
DISPLAY 0.680851 (-12840 7810);
PAINT MONO (-12840 7810);
FORCEPROP 0 LASTPIN (-12850 7700) $PN M12
J 0
(-12840 7710);
DISPLAY 0.680851 (-12840 7710);
PAINT MONO (-12840 7710);
FORCEPROP 0 LASTPIN (-12850 7600) $PN P12
J 0
(-12840 7610);
DISPLAY 0.680851 (-12840 7610);
PAINT MONO (-12840 7610);
FORCEPROP 0 LASTPIN (-12850 7500) $PN R11
J 0
(-12840 7510);
DISPLAY 0.680851 (-12840 7510);
PAINT MONO (-12840 7510);
FORCEPROP 0 LASTPIN (-12850 7300) $PN E12
J 0
(-12840 7310);
DISPLAY 0.680851 (-12840 7310);
PAINT MONO (-12840 7310);
FORCEPROP 0 LASTPIN (-12850 7200) $PN J11
J 0
(-12840 7210);
DISPLAY 0.680851 (-12840 7210);
PAINT MONO (-12840 7210);
FORCEPROP 0 LASTPIN (-12850 7100) $PN L11
J 0
(-12840 7110);
DISPLAY 0.680851 (-12840 7110);
PAINT MONO (-12840 7110);
FORCEPROP 0 LASTPIN (-12850 7000) $PN N11
J 0
(-12840 7010);
DISPLAY 0.680851 (-12840 7010);
PAINT MONO (-12840 7010);
FORCEPROP 0 LASTPIN (-12850 6800) $PN H10
J 0
(-12840 6810);
DISPLAY 0.680851 (-12840 6810);
PAINT MONO (-12840 6810);
FORCEPROP 0 LASTPIN (-12850 6700) $PN H8
J 0
(-12840 6710);
DISPLAY 0.680851 (-12840 6710);
PAINT MONO (-12840 6710);
FORCEPROP 0 LASTPIN (-12850 6600) $PN J7
J 0
(-12840 6610);
DISPLAY 0.680851 (-12840 6610);
PAINT MONO (-12840 6610);
FORCEPROP 0 LASTPIN (-12850 6500) $PN J9
J 0
(-12840 6510);
DISPLAY 0.680851 (-12840 6510);
PAINT MONO (-12840 6510);
FORCEPROP 0 LASTPIN (-12850 6400) $PN K8
J 0
(-12840 6410);
DISPLAY 0.680851 (-12840 6410);
PAINT MONO (-12840 6410);
FORCEPROP 0 LASTPIN (-12850 6300) $PN L7
J 0
(-12840 6310);
DISPLAY 0.680851 (-12840 6310);
PAINT MONO (-12840 6310);
FORCEPROP 0 LASTPIN (-12850 6200) $PN M8
J 0
(-12840 6210);
DISPLAY 0.680851 (-12840 6210);
PAINT MONO (-12840 6210);
FORCEPROP 0 LASTPIN (-12850 6100) $PN N7
J 0
(-12840 6110);
DISPLAY 0.680851 (-12840 6110);
PAINT MONO (-12840 6110);
FORCEPROP 0 LASTPIN (-12850 6000) $PN P10
J 0
(-12840 6010);
DISPLAY 0.680851 (-12840 6010);
PAINT MONO (-12840 6010);
FORCEPROP 0 LASTPIN (-12850 5900) $PN P8
J 0
(-12840 5910);
DISPLAY 0.680851 (-12840 5910);
PAINT MONO (-12840 5910);
FORCEPROP 0 LASTPIN (-12850 5800) $PN R7
J 0
(-12840 5810);
DISPLAY 0.680851 (-12840 5810);
PAINT MONO (-12840 5810);
FORCEPROP 0 LASTPIN (-12850 5700) $PN R9
J 0
(-12840 5710);
DISPLAY 0.680851 (-12840 5710);
PAINT MONO (-12840 5710);
FORCEPROP 0 LASTPIN (-12850 5600) $PN T10
J 0
(-12840 5610);
DISPLAY 0.680851 (-12840 5610);
PAINT MONO (-12840 5610);
FORCEPROP 0 LASTPIN (-12850 5500) $PN T8
J 0
(-12840 5510);
DISPLAY 0.680851 (-12840 5510);
PAINT MONO (-12840 5510);
FORCEPROP 0 LASTPIN (-12850 5300) $PN F12
J 0
(-12840 5310);
DISPLAY 0.680851 (-12840 5310);
PAINT MONO (-12840 5310);
FORCEPROP 0 LASTPIN (-12850 5200) $PN T12
J 0
(-12840 5210);
DISPLAY 0.680851 (-12840 5210);
PAINT MONO (-12840 5210);
FORCEPROP 0 LASTPIN (-12850 5000) $PN AA17
J 0
(-12840 5010);
DISPLAY 0.680851 (-12840 5010);
PAINT MONO (-12840 5010);
FORCEPROP 0 LASTPIN (-12850 4900) $PN AB14
J 0
(-12840 4910);
DISPLAY 0.680851 (-12840 4910);
PAINT MONO (-12840 4910);
FORCEPROP 0 LASTPIN (-12850 4800) $PN V16
J 0
(-12840 4810);
DISPLAY 0.680851 (-12840 4810);
PAINT MONO (-12840 4810);
FORCEPROP 0 LASTPIN (-12850 4700) $PN W13
J 0
(-12840 4710);
DISPLAY 0.680851 (-12840 4710);
PAINT MONO (-12840 4710);
FORCEPROP 0 LASTPIN (-12850 4600) $PN Y10
J 0
(-12840 4610);
DISPLAY 0.680851 (-12840 4610);
PAINT MONO (-12840 4610);
FORCEPROP 0 LASTPIN (-12850 4400) $PN M14
J 0
(-12840 4410);
DISPLAY 0.680851 (-12840 4410);
PAINT MONO (-12840 4410);
FORCEPROP 0 LASTPIN (-12850 4300) $PN P18
J 0
(-12840 4310);
DISPLAY 0.680851 (-12840 4310);
PAINT MONO (-12840 4310);
FORCEPROP 0 LASTPIN (-12850 4200) $PN R15
J 0
(-12840 4210);
DISPLAY 0.680851 (-12840 4210);
PAINT MONO (-12840 4210);
FORCEPROP 0 LASTPIN (-12850 4100) $PN T22
J 0
(-12840 4110);
DISPLAY 0.680851 (-12840 4110);
PAINT MONO (-12840 4110);
FORCEPROP 0 LASTPIN (-12850 4000) $PN U19
J 0
(-12840 4010);
DISPLAY 0.680851 (-12840 4010);
PAINT MONO (-12840 4010);
FORCEPROP 0 LASTPIN (-12850 3900) $PN Y20
J 0
(-12840 3910);
DISPLAY 0.680851 (-12840 3910);
PAINT MONO (-12840 3910);
FORCEPROP 0 LASTPIN (-12850 3700) $PN G19
J 0
(-12840 3710);
DISPLAY 0.680851 (-12840 3710);
PAINT MONO (-12840 3710);
FORCEPROP 0 LASTPIN (-12850 3600) $PN H16
J 0
(-12840 3610);
DISPLAY 0.680851 (-12840 3610);
PAINT MONO (-12840 3610);
FORCEPROP 0 LASTPIN (-12850 3500) $PN J13
J 0
(-12840 3510);
DISPLAY 0.680851 (-12840 3510);
PAINT MONO (-12840 3510);
FORCEPROP 0 LASTPIN (-12850 3400) $PN K20
J 0
(-12840 3410);
DISPLAY 0.680851 (-12840 3410);
PAINT MONO (-12840 3410);
FORCEPROP 0 LASTPIN (-12850 3300) $PN L17
J 0
(-12840 3310);
DISPLAY 0.680851 (-12840 3310);
PAINT MONO (-12840 3310);
FORCEPROP 0 LASTPIN (-12850 3200) $PN N21
J 0
(-12840 3210);
DISPLAY 0.680851 (-12840 3210);
PAINT MONO (-12840 3210);
FORCEPROP 0 LASTPIN (-12850 3000) $PN A17
J 0
(-12840 3010);
DISPLAY 0.680851 (-12840 3010);
PAINT MONO (-12840 3010);
FORCEPROP 0 LASTPIN (-12850 2900) $PN B14
J 0
(-12840 2910);
DISPLAY 0.680851 (-12840 2910);
PAINT MONO (-12840 2910);
FORCEPROP 0 LASTPIN (-12850 2800) $PN C21
J 0
(-12840 2810);
DISPLAY 0.680851 (-12840 2810);
PAINT MONO (-12840 2810);
FORCEPROP 0 LASTPIN (-12850 2700) $PN D18
J 0
(-12840 2710);
DISPLAY 0.680851 (-12840 2710);
PAINT MONO (-12840 2710);
FORCEPROP 0 LASTPIN (-12850 2600) $PN E15
J 0
(-12840 2610);
DISPLAY 0.680851 (-12840 2610);
PAINT MONO (-12840 2610);
FORCEPROP 0 LASTPIN (-12850 2500) $PN F22
J 0
(-12840 2510);
DISPLAY 0.680851 (-12840 2510);
PAINT MONO (-12840 2510);
FORCEPROP 0 LASTPIN (-12850 2300) $PN AA7
J 0
(-12840 2310);
DISPLAY 0.680851 (-12840 2310);
PAINT MONO (-12840 2310);
FORCEPROP 0 LASTPIN (-12850 2200) $PN AB4
J 0
(-12840 2210);
DISPLAY 0.680851 (-12840 2210);
PAINT MONO (-12840 2210);
FORCEPROP 0 LASTPIN (-12850 2100) $PN R5
J 0
(-12840 2110);
DISPLAY 0.680851 (-12840 2110);
PAINT MONO (-12840 2110);
FORCEPROP 0 LASTPIN (-12850 2000) $PN T2
J 0
(-12840 2010);
DISPLAY 0.680851 (-12840 2010);
PAINT MONO (-12840 2010);
FORCEPROP 0 LASTPIN (-12850 1900) $PN V6
J 0
(-12840 1910);
DISPLAY 0.680851 (-12840 1910);
PAINT MONO (-12840 1910);
FORCEPROP 0 LASTPIN (-12850 1800) $PN W3
J 0
(-12840 1810);
DISPLAY 0.680851 (-12840 1810);
PAINT MONO (-12840 1810);
FORCEPROP 0 LASTPIN (-12850 1600) $PN C1
J 0
(-12840 1610);
DISPLAY 0.680851 (-12840 1610);
PAINT MONO (-12840 1610);
FORCEPROP 0 LASTPIN (-12850 1500) $PN F2
J 0
(-12840 1510);
DISPLAY 0.680851 (-12840 1510);
PAINT MONO (-12840 1510);
FORCEPROP 0 LASTPIN (-12850 1400) $PN H6
J 0
(-12840 1410);
DISPLAY 0.680851 (-12840 1410);
PAINT MONO (-12840 1410);
FORCEPROP 0 LASTPIN (-12850 1300) $PN J3
J 0
(-12840 1310);
DISPLAY 0.680851 (-12840 1310);
PAINT MONO (-12840 1310);
FORCEPROP 0 LASTPIN (-12850 1200) $PN M4
J 0
(-12840 1210);
DISPLAY 0.680851 (-12840 1210);
PAINT MONO (-12840 1210);
FORCEPROP 0 LASTPIN (-12850 1100) $PN N1
J 0
(-12840 1110);
DISPLAY 0.680851 (-12840 1110);
PAINT MONO (-12840 1110);
FORCEPROP 0 LAST CDS_LOCATION U24
J 0
(-12950 8500);
DISPLAY 1.021277 (-12950 8500);
DISPLAY INVISIBLE (-12950 8500);
FORCEPROP 0 LAST $SEC 5
J 0
(-12950 8500);
DISPLAY 0.680851 (-12950 8500);
PAINT MONO (-12950 8500);
DISPLAY INVISIBLE (-12950 8500);
FORCEPROP 0 LAST CDS_SEC 5
J 0
(-12950 8500);
DISPLAY 1.021277 (-12950 8500);
DISPLAY INVISIBLE (-12950 8500);
FORCEADD FERRITEBEAD..1
(-3350 6000);
FORCEPROP 0 LAST PACKAGE 0603
J 0
(-3350 6050);
DISPLAY 1.021277 (-3350 6050);
FORCEPROP 1 LAST VALUE 120OHM
J 0
(-3100 6000);
DISPLAY 1.212766 (-3100 6000);
PAINT GREEN (-3100 6000);
FORCEPROP 1 LAST TOLERANCE 25%
J 0
(-3450 6050);
DISPLAY 1.212766 (-3450 6050);
PAINT GREEN (-3450 6050);
DISPLAY INVISIBLE (-3450 6050);
FORCEPROP 1 LAST PATH I139
J 2
(-3400 6050);
DISPLAY 1.212766 (-3400 6050);
PAINT GREEN (-3400 6050);
DISPLAY INVISIBLE (-3400 6050);
FORCEPROP 2 LAST CDS_LIB passive
J 0
(-3350 6000);
DISPLAY INVISIBLE (-3350 6000);
FORCEPROP 1 LAST CDS_LMAN_SYM_OUTLINE 0,0,200,-100
J 0
(-3350 6000);
DISPLAY 0.468085 (-3350 6000);
PAINT GREEN (-3350 6000);
DISPLAY INVISIBLE (-3350 6000);
FORCEPROP 1 LAST CLS_PN G191-10100-01
J 2
(-3400 6050);
DISPLAY 1.212766 (-3400 6050);
PAINT GREEN (-3400 6050);
DISPLAY INVISIBLE (-3400 6050);
FORCEPROP 1 LAST $LOCATION L12
J 2
(-3450 6000);
DISPLAY 1.212766 (-3450 6000);
PAINT GREEN (-3450 6000);
FORCEPROP 0 LASTPIN (-3450 5950) $PN 1
J 2
(-3460 5960);
DISPLAY 0.680851 (-3460 5960);
PAINT MONO (-3460 5960);
FORCEPROP 0 LASTPIN (-3050 5950) $PN 2
J 0
(-3040 5960);
DISPLAY 0.680851 (-3040 5960);
PAINT MONO (-3040 5960);
FORCEPROP 0 LAST CDS_LOCATION L12
J 0
(-3100 6100);
DISPLAY 1.021277 (-3100 6100);
DISPLAY INVISIBLE (-3100 6100);
FORCEPROP 0 LAST $SEC 1
J 0
(-3100 6100);
DISPLAY 0.680851 (-3100 6100);
PAINT MONO (-3100 6100);
DISPLAY INVISIBLE (-3100 6100);
FORCEPROP 0 LAST CDS_SEC 1
J 0
(-3100 6100);
DISPLAY 1.021277 (-3100 6100);
DISPLAY INVISIBLE (-3100 6100);
FORCEADD CAPACITOR..2
(-3950 5700);
FORCEPROP 0 LAST VOLTAGE 6.3V
J 0
(-3900 5850);
DISPLAY 1.021277 (-3900 5850);
FORCEPROP 0 LAST PACKAGE 1210
J 0
(-3900 5950);
DISPLAY 1.021277 (-3900 5950);
FORCEPROP 1 LAST VALUE 100UF
J 0
(-3900 5750);
DISPLAY 1.212766 (-3900 5750);
PAINT GREEN (-3900 5750);
FORCEPROP 1 LAST PATH I172
J 0
(-4050 5750);
DISPLAY 1.212766 (-4050 5750);
PAINT GREEN (-4050 5750);
DISPLAY INVISIBLE (-4050 5750);
FORCEPROP 1 LAST TOLERANCE 20%
J 0
(-4100 5800);
DISPLAY 1.212766 (-4100 5800);
PAINT GREEN (-4100 5800);
DISPLAY INVISIBLE (-4100 5800);
FORCEPROP 1 LAST CLS_PN G109-0G107-BM
J 0
(-4050 5750);
DISPLAY 1.212766 (-4050 5750);
PAINT GREEN (-4050 5750);
DISPLAY INVISIBLE (-4050 5750);
FORCEPROP 1 LAST CDS_LMAN_SYM_OUTLINE -50,0,50,-50
J 0
(-3950 5700);
DISPLAY 0.468085 (-3950 5700);
PAINT GREEN (-3950 5700);
DISPLAY INVISIBLE (-3950 5700);
FORCEPROP 2 LAST CDS_LIB passive
J 0
(-3950 5700);
DISPLAY INVISIBLE (-3950 5700);
FORCEPROP 1 LAST $LOCATION C176
J 0
(-3900 5550);
DISPLAY 1.212766 (-3900 5550);
PAINT GREEN (-3900 5550);
FORCEPROP 0 LASTPIN (-3950 5800) $PN 1
R 1
J 0
(-3960 5810);
DISPLAY 0.680851 (-3960 5810);
PAINT MONO (-3960 5810);
FORCEPROP 0 LASTPIN (-3950 5550) $PN 2
R 1
J 2
(-3960 5540);
DISPLAY 0.680851 (-3960 5540);
PAINT MONO (-3960 5540);
FORCEPROP 0 LAST CDS_LOCATION C176
J 0
(-3900 5900);
DISPLAY 1.021277 (-3900 5900);
DISPLAY INVISIBLE (-3900 5900);
FORCEPROP 0 LAST $SEC 1
J 0
(-3900 5900);
DISPLAY 0.680851 (-3900 5900);
PAINT MONO (-3900 5900);
DISPLAY INVISIBLE (-3900 5900);
FORCEPROP 0 LAST CDS_SEC 1
J 0
(-3900 5900);
DISPLAY 1.021277 (-3900 5900);
DISPLAY INVISIBLE (-3900 5900);
FORCEADD CAPACITOR..2
(-4300 5700);
FORCEPROP 0 LAST VOLTAGE 6.3V
J 0
(-4250 5850);
DISPLAY 1.021277 (-4250 5850);
FORCEPROP 0 LAST PACKAGE 1210
J 0
(-4250 5950);
DISPLAY 1.021277 (-4250 5950);
FORCEPROP 1 LAST VALUE 100UF
J 0
(-4250 5750);
DISPLAY 1.212766 (-4250 5750);
PAINT GREEN (-4250 5750);
FORCEPROP 1 LAST PATH I173
J 0
(-4400 5750);
DISPLAY 1.212766 (-4400 5750);
PAINT GREEN (-4400 5750);
DISPLAY INVISIBLE (-4400 5750);
FORCEPROP 1 LAST TOLERANCE 20%
J 0
(-4450 5800);
DISPLAY 1.212766 (-4450 5800);
PAINT GREEN (-4450 5800);
DISPLAY INVISIBLE (-4450 5800);
FORCEPROP 1 LAST CLS_PN G109-0G107-BM
J 0
(-4400 5750);
DISPLAY 1.212766 (-4400 5750);
PAINT GREEN (-4400 5750);
DISPLAY INVISIBLE (-4400 5750);
FORCEPROP 2 LAST CDS_LIB passive
J 0
(-4300 5700);
DISPLAY INVISIBLE (-4300 5700);
FORCEPROP 1 LAST CDS_LMAN_SYM_OUTLINE -50,0,50,-50
J 0
(-4300 5700);
DISPLAY 0.468085 (-4300 5700);
PAINT GREEN (-4300 5700);
DISPLAY INVISIBLE (-4300 5700);
FORCEPROP 1 LAST $LOCATION C175
J 0
(-4250 5550);
DISPLAY 1.212766 (-4250 5550);
PAINT GREEN (-4250 5550);
FORCEPROP 0 LASTPIN (-4300 5800) $PN 1
R 1
J 0
(-4310 5810);
DISPLAY 0.680851 (-4310 5810);
PAINT MONO (-4310 5810);
FORCEPROP 0 LASTPIN (-4300 5550) $PN 2
R 1
J 2
(-4310 5540);
DISPLAY 0.680851 (-4310 5540);
PAINT MONO (-4310 5540);
FORCEPROP 0 LAST CDS_LOCATION C175
J 0
(-4250 5900);
DISPLAY 1.021277 (-4250 5900);
DISPLAY INVISIBLE (-4250 5900);
FORCEPROP 0 LAST $SEC 1
J 0
(-4250 5900);
DISPLAY 0.680851 (-4250 5900);
PAINT MONO (-4250 5900);
DISPLAY INVISIBLE (-4250 5900);
FORCEPROP 0 LAST CDS_SEC 1
J 0
(-4250 5900);
DISPLAY 1.021277 (-4250 5900);
DISPLAY INVISIBLE (-4250 5900);
FORCEADD CAPACITOR..2
(-5000 4300);
FORCEPROP 1 LAST VALUE 100UF
J 0
(-4950 4350);
DISPLAY 1.212766 (-4950 4350);
PAINT GREEN (-4950 4350);
FORCEPROP 0 LAST VOLTAGE 6.3V
J 0
(-4950 4450);
DISPLAY 1.021277 (-4950 4450);
FORCEPROP 0 LAST PACKAGE 1210
J 0
(-4950 4550);
DISPLAY 1.021277 (-4950 4550);
FORCEPROP 1 LAST PATH I174
J 0
(-5100 4350);
DISPLAY 1.212766 (-5100 4350);
PAINT GREEN (-5100 4350);
DISPLAY INVISIBLE (-5100 4350);
FORCEPROP 1 LAST CLS_PN G109-0G107-BM
J 0
(-5100 4350);
DISPLAY 1.212766 (-5100 4350);
PAINT GREEN (-5100 4350);
DISPLAY INVISIBLE (-5100 4350);
FORCEPROP 1 LAST CDS_LMAN_SYM_OUTLINE -50,0,50,-50
J 0
(-5000 4300);
DISPLAY 0.468085 (-5000 4300);
PAINT GREEN (-5000 4300);
DISPLAY INVISIBLE (-5000 4300);
FORCEPROP 2 LAST CDS_LIB passive
J 0
(-5000 4300);
DISPLAY INVISIBLE (-5000 4300);
FORCEPROP 1 LAST TOLERANCE 20%
J 0
(-5150 4400);
DISPLAY 1.212766 (-5150 4400);
PAINT GREEN (-5150 4400);
DISPLAY INVISIBLE (-5150 4400);
FORCEPROP 1 LAST $LOCATION C172
J 0
(-4950 4150);
DISPLAY 1.212766 (-4950 4150);
PAINT GREEN (-4950 4150);
FORCEPROP 0 LASTPIN (-5000 4400) $PN 1
R 1
J 0
(-5010 4410);
DISPLAY 0.680851 (-5010 4410);
PAINT MONO (-5010 4410);
FORCEPROP 0 LASTPIN (-5000 4150) $PN 2
R 1
J 2
(-5010 4140);
DISPLAY 0.680851 (-5010 4140);
PAINT MONO (-5010 4140);
FORCEPROP 0 LAST CDS_LOCATION C172
J 0
(-4950 4500);
DISPLAY 1.021277 (-4950 4500);
DISPLAY INVISIBLE (-4950 4500);
FORCEPROP 0 LAST $SEC 1
J 0
(-4950 4500);
DISPLAY 0.680851 (-4950 4500);
PAINT MONO (-4950 4500);
DISPLAY INVISIBLE (-4950 4500);
FORCEPROP 0 LAST CDS_SEC 1
J 0
(-4950 4500);
DISPLAY 1.021277 (-4950 4500);
DISPLAY INVISIBLE (-4950 4500);
FORCEADD CAPACITOR..2
(-6400 7150);
FORCEPROP 0 LAST VOLTAGE 10V
J 0
(-6350 7300);
DISPLAY 1.021277 (-6350 7300);
FORCEPROP 1 LAST VALUE 22UF
J 0
(-6350 7200);
DISPLAY 1.212766 (-6350 7200);
PAINT GREEN (-6350 7200);
FORCEPROP 0 LAST PACKAGE 0805
J 0
(-6350 7400);
DISPLAY 1.021277 (-6350 7400);
FORCEPROP 1 LAST PATH I176
J 0
(-6500 7200);
DISPLAY 1.212766 (-6500 7200);
PAINT GREEN (-6500 7200);
DISPLAY INVISIBLE (-6500 7200);
FORCEPROP 1 LAST CLS_PN G107-0F226-CM
J 0
(-6500 7200);
DISPLAY 1.212766 (-6500 7200);
PAINT GREEN (-6500 7200);
DISPLAY INVISIBLE (-6500 7200);
FORCEPROP 1 LAST TOLERANCE 20%
J 0
(-6550 7250);
DISPLAY 1.212766 (-6550 7250);
PAINT GREEN (-6550 7250);
DISPLAY INVISIBLE (-6550 7250);
FORCEPROP 2 LAST CDS_LIB passive
J 0
(-6400 7150);
DISPLAY INVISIBLE (-6400 7150);
FORCEPROP 1 LAST CDS_LMAN_SYM_OUTLINE -50,0,50,-50
J 0
(-6400 7150);
DISPLAY 0.468085 (-6400 7150);
PAINT GREEN (-6400 7150);
DISPLAY INVISIBLE (-6400 7150);
FORCEPROP 1 LAST $LOCATION C158
J 0
(-6350 7000);
DISPLAY 1.212766 (-6350 7000);
PAINT GREEN (-6350 7000);
FORCEPROP 0 LASTPIN (-6400 7250) $PN 1
R 1
J 0
(-6410 7260);
DISPLAY 0.680851 (-6410 7260);
PAINT MONO (-6410 7260);
FORCEPROP 0 LASTPIN (-6400 7000) $PN 2
R 1
J 2
(-6410 6990);
DISPLAY 0.680851 (-6410 6990);
PAINT MONO (-6410 6990);
FORCEPROP 0 LAST CDS_LOCATION C158
J 0
(-6350 7350);
DISPLAY 1.021277 (-6350 7350);
DISPLAY INVISIBLE (-6350 7350);
FORCEPROP 0 LAST $SEC 1
J 0
(-6350 7350);
DISPLAY 0.680851 (-6350 7350);
PAINT MONO (-6350 7350);
DISPLAY INVISIBLE (-6350 7350);
FORCEPROP 0 LAST CDS_SEC 1
J 0
(-6350 7350);
DISPLAY 1.021277 (-6350 7350);
DISPLAY INVISIBLE (-6350 7350);
FORCEADD CAPACITOR..2
(-8750 7150);
FORCEPROP 0 LAST VOLTAGE 6.3V
J 0
(-8700 7300);
DISPLAY 1.021277 (-8700 7300);
FORCEPROP 1 LAST VALUE 4.7UF
J 0
(-8700 7200);
DISPLAY 1.212766 (-8700 7200);
PAINT GREEN (-8700 7200);
FORCEPROP 0 LAST PACKAGE 0402
J 0
(-8700 7400);
DISPLAY 1.021277 (-8700 7400);
FORCEPROP 1 LAST PATH I177
J 0
(-8850 7200);
DISPLAY 1.212766 (-8850 7200);
PAINT GREEN (-8850 7200);
DISPLAY INVISIBLE (-8850 7200);
FORCEPROP 1 LAST CLS_PN G105-0F475-BM
J 0
(-8850 7200);
DISPLAY 1.212766 (-8850 7200);
PAINT GREEN (-8850 7200);
DISPLAY INVISIBLE (-8850 7200);
FORCEPROP 2 LAST CDS_LIB passive
J 0
(-8750 7150);
DISPLAY INVISIBLE (-8750 7150);
FORCEPROP 1 LAST CDS_LMAN_SYM_OUTLINE -50,0,50,-50
J 0
(-8750 7150);
DISPLAY 0.468085 (-8750 7150);
PAINT GREEN (-8750 7150);
DISPLAY INVISIBLE (-8750 7150);
FORCEPROP 1 LAST TOLERANCE 20%
J 0
(-8900 7250);
DISPLAY 1.212766 (-8900 7250);
PAINT GREEN (-8900 7250);
DISPLAY INVISIBLE (-8900 7250);
FORCEPROP 1 LAST $LOCATION C120
J 0
(-8700 7000);
DISPLAY 1.212766 (-8700 7000);
PAINT GREEN (-8700 7000);
FORCEPROP 0 LASTPIN (-8750 7250) $PN 1
R 1
J 0
(-8760 7260);
DISPLAY 0.680851 (-8760 7260);
PAINT MONO (-8760 7260);
FORCEPROP 0 LASTPIN (-8750 7000) $PN 2
R 1
J 2
(-8760 6990);
DISPLAY 0.680851 (-8760 6990);
PAINT MONO (-8760 6990);
FORCEPROP 0 LAST CDS_LOCATION C120
J 0
(-8700 7350);
DISPLAY 1.021277 (-8700 7350);
DISPLAY INVISIBLE (-8700 7350);
FORCEPROP 0 LAST $SEC 1
J 0
(-8700 7350);
DISPLAY 0.680851 (-8700 7350);
PAINT MONO (-8700 7350);
DISPLAY INVISIBLE (-8700 7350);
FORCEPROP 0 LAST CDS_SEC 1
J 0
(-8700 7350);
DISPLAY 1.021277 (-8700 7350);
DISPLAY INVISIBLE (-8700 7350);
FORCEADD CAPACITOR..2
(-4600 4300);
FORCEPROP 0 LAST VOLTAGE 6.3V
J 0
(-4550 4450);
DISPLAY 1.021277 (-4550 4450);
FORCEPROP 1 LAST VALUE 100UF
J 0
(-4550 4350);
DISPLAY 1.212766 (-4550 4350);
PAINT GREEN (-4550 4350);
FORCEPROP 0 LAST PACKAGE 1210
J 0
(-4550 4550);
DISPLAY 1.021277 (-4550 4550);
FORCEPROP 1 LAST PATH I178
J 0
(-4700 4350);
DISPLAY 1.212766 (-4700 4350);
PAINT GREEN (-4700 4350);
DISPLAY INVISIBLE (-4700 4350);
FORCEPROP 1 LAST TOLERANCE 20%
J 0
(-4750 4400);
DISPLAY 1.212766 (-4750 4400);
PAINT GREEN (-4750 4400);
DISPLAY INVISIBLE (-4750 4400);
FORCEPROP 1 LAST CLS_PN G109-0G107-BM
J 0
(-4700 4350);
DISPLAY 1.212766 (-4700 4350);
PAINT GREEN (-4700 4350);
DISPLAY INVISIBLE (-4700 4350);
FORCEPROP 1 LAST CDS_LMAN_SYM_OUTLINE -50,0,50,-50
J 0
(-4600 4300);
DISPLAY 0.468085 (-4600 4300);
PAINT GREEN (-4600 4300);
DISPLAY INVISIBLE (-4600 4300);
FORCEPROP 2 LAST CDS_LIB passive
J 0
(-4600 4300);
DISPLAY INVISIBLE (-4600 4300);
FORCEPROP 1 LAST $LOCATION C174
J 0
(-4550 4150);
DISPLAY 1.212766 (-4550 4150);
PAINT GREEN (-4550 4150);
FORCEPROP 0 LASTPIN (-4600 4400) $PN 1
R 1
J 0
(-4610 4410);
DISPLAY 0.680851 (-4610 4410);
PAINT MONO (-4610 4410);
FORCEPROP 0 LASTPIN (-4600 4150) $PN 2
R 1
J 2
(-4610 4140);
DISPLAY 0.680851 (-4610 4140);
PAINT MONO (-4610 4140);
FORCEPROP 0 LAST CDS_LOCATION C174
J 0
(-4550 4500);
DISPLAY 1.021277 (-4550 4500);
DISPLAY INVISIBLE (-4550 4500);
FORCEPROP 0 LAST $SEC 1
J 0
(-4550 4500);
DISPLAY 0.680851 (-4550 4500);
PAINT MONO (-4550 4500);
DISPLAY INVISIBLE (-4550 4500);
FORCEPROP 0 LAST CDS_SEC 1
J 0
(-4550 4500);
DISPLAY 1.021277 (-4550 4500);
DISPLAY INVISIBLE (-4550 4500);
FORCEADD CAPACITOR..2
(-10950 5700);
FORCEPROP 1 LAST VALUE 0.1UF
J 0
(-10900 5750);
DISPLAY 1.212766 (-10900 5750);
PAINT GREEN (-10900 5750);
FORCEPROP 0 LAST VOLTAGE 10V
J 0
(-10900 5850);
DISPLAY 1.021277 (-10900 5850);
FORCEPROP 0 LAST PACKAGE 0402
J 0
(-10900 5950);
DISPLAY 1.021277 (-10900 5950);
FORCEPROP 1 LAST PATH I182
J 0
(-11050 5750);
DISPLAY 1.212766 (-11050 5750);
PAINT GREEN (-11050 5750);
DISPLAY INVISIBLE (-11050 5750);
FORCEPROP 1 LAST TOLERANCE 10%
J 0
(-11100 5800);
DISPLAY 1.212766 (-11100 5800);
PAINT GREEN (-11100 5800);
DISPLAY INVISIBLE (-11100 5800);
FORCEPROP 2 LAST CDS_LIB passive
J 0
(-10950 5700);
DISPLAY INVISIBLE (-10950 5700);
FORCEPROP 1 LAST CDS_LMAN_SYM_OUTLINE -50,0,50,-50
J 0
(-10950 5700);
DISPLAY 0.468085 (-10950 5700);
PAINT GREEN (-10950 5700);
DISPLAY INVISIBLE (-10950 5700);
FORCEPROP 1 LAST CLS_PN G105-0B104-CK
J 0
(-11050 5750);
DISPLAY 1.212766 (-11050 5750);
PAINT GREEN (-11050 5750);
DISPLAY INVISIBLE (-11050 5750);
FORCEPROP 1 LAST $LOCATION C201
J 0
(-10900 5550);
DISPLAY 1.212766 (-10900 5550);
PAINT GREEN (-10900 5550);
FORCEPROP 0 LASTPIN (-10950 5800) $PN 1
R 1
J 0
(-10960 5810);
DISPLAY 0.680851 (-10960 5810);
PAINT MONO (-10960 5810);
FORCEPROP 0 LASTPIN (-10950 5550) $PN 2
R 1
J 2
(-10960 5540);
DISPLAY 0.680851 (-10960 5540);
PAINT MONO (-10960 5540);
FORCEPROP 0 LAST CDS_LOCATION C201
J 0
(-10900 5900);
DISPLAY 1.021277 (-10900 5900);
DISPLAY INVISIBLE (-10900 5900);
FORCEPROP 0 LAST $SEC 1
J 0
(-10900 5900);
DISPLAY 0.680851 (-10900 5900);
PAINT MONO (-10900 5900);
DISPLAY INVISIBLE (-10900 5900);
FORCEPROP 0 LAST CDS_SEC 1
J 0
(-10900 5900);
DISPLAY 1.021277 (-10900 5900);
DISPLAY INVISIBLE (-10900 5900);
FORCEADD CAPACITOR..2
(-10600 5700);
FORCEPROP 1 LAST VALUE 0.1UF
J 0
(-10550 5750);
DISPLAY 1.212766 (-10550 5750);
PAINT GREEN (-10550 5750);
FORCEPROP 0 LAST VOLTAGE 10V
J 0
(-10550 5850);
DISPLAY 1.021277 (-10550 5850);
FORCEPROP 0 LAST PACKAGE 0402
J 0
(-10550 5950);
DISPLAY 1.021277 (-10550 5950);
FORCEPROP 1 LAST PATH I183
J 0
(-10700 5750);
DISPLAY 1.212766 (-10700 5750);
PAINT GREEN (-10700 5750);
DISPLAY INVISIBLE (-10700 5750);
FORCEPROP 1 LAST TOLERANCE 10%
J 0
(-10750 5800);
DISPLAY 1.212766 (-10750 5800);
PAINT GREEN (-10750 5800);
DISPLAY INVISIBLE (-10750 5800);
FORCEPROP 2 LAST CDS_LIB passive
J 0
(-10600 5700);
DISPLAY INVISIBLE (-10600 5700);
FORCEPROP 1 LAST CDS_LMAN_SYM_OUTLINE -50,0,50,-50
J 0
(-10600 5700);
DISPLAY 0.468085 (-10600 5700);
PAINT GREEN (-10600 5700);
DISPLAY INVISIBLE (-10600 5700);
FORCEPROP 1 LAST CLS_PN G105-0B104-CK
J 0
(-10700 5750);
DISPLAY 1.212766 (-10700 5750);
PAINT GREEN (-10700 5750);
DISPLAY INVISIBLE (-10700 5750);
FORCEPROP 1 LAST $LOCATION C207
J 0
(-10550 5550);
DISPLAY 1.212766 (-10550 5550);
PAINT GREEN (-10550 5550);
FORCEPROP 0 LASTPIN (-10600 5800) $PN 1
R 1
J 0
(-10610 5810);
DISPLAY 0.680851 (-10610 5810);
PAINT MONO (-10610 5810);
FORCEPROP 0 LASTPIN (-10600 5550) $PN 2
R 1
J 2
(-10610 5540);
DISPLAY 0.680851 (-10610 5540);
PAINT MONO (-10610 5540);
FORCEPROP 0 LAST CDS_LOCATION C207
J 0
(-10550 5900);
DISPLAY 1.021277 (-10550 5900);
DISPLAY INVISIBLE (-10550 5900);
FORCEPROP 0 LAST $SEC 1
J 0
(-10550 5900);
DISPLAY 0.680851 (-10550 5900);
PAINT MONO (-10550 5900);
DISPLAY INVISIBLE (-10550 5900);
FORCEPROP 0 LAST CDS_SEC 1
J 0
(-10550 5900);
DISPLAY 1.021277 (-10550 5900);
DISPLAY INVISIBLE (-10550 5900);
FORCEADD CAPACITOR..2
(-10200 5700);
FORCEPROP 1 LAST VALUE 0.1UF
J 0
(-10150 5750);
DISPLAY 1.212766 (-10150 5750);
PAINT GREEN (-10150 5750);
FORCEPROP 0 LAST VOLTAGE 10V
J 0
(-10150 5850);
DISPLAY 1.021277 (-10150 5850);
FORCEPROP 0 LAST PACKAGE 0402
J 0
(-10150 5950);
DISPLAY 1.021277 (-10150 5950);
FORCEPROP 1 LAST PATH I184
J 0
(-10300 5750);
DISPLAY 1.212766 (-10300 5750);
PAINT GREEN (-10300 5750);
DISPLAY INVISIBLE (-10300 5750);
FORCEPROP 1 LAST TOLERANCE 10%
J 0
(-10350 5800);
DISPLAY 1.212766 (-10350 5800);
PAINT GREEN (-10350 5800);
DISPLAY INVISIBLE (-10350 5800);
FORCEPROP 2 LAST CDS_LIB passive
J 0
(-10200 5700);
DISPLAY INVISIBLE (-10200 5700);
FORCEPROP 1 LAST CDS_LMAN_SYM_OUTLINE -50,0,50,-50
J 0
(-10200 5700);
DISPLAY 0.468085 (-10200 5700);
PAINT GREEN (-10200 5700);
DISPLAY INVISIBLE (-10200 5700);
FORCEPROP 1 LAST CLS_PN G105-0B104-CK
J 0
(-10300 5750);
DISPLAY 1.212766 (-10300 5750);
PAINT GREEN (-10300 5750);
DISPLAY INVISIBLE (-10300 5750);
FORCEPROP 1 LAST $LOCATION C214
J 0
(-10150 5550);
DISPLAY 1.212766 (-10150 5550);
PAINT GREEN (-10150 5550);
FORCEPROP 0 LASTPIN (-10200 5800) $PN 1
R 1
J 0
(-10210 5810);
DISPLAY 0.680851 (-10210 5810);
PAINT MONO (-10210 5810);
FORCEPROP 0 LASTPIN (-10200 5550) $PN 2
R 1
J 2
(-10210 5540);
DISPLAY 0.680851 (-10210 5540);
PAINT MONO (-10210 5540);
FORCEPROP 0 LAST CDS_LOCATION C214
J 0
(-10150 5900);
DISPLAY 1.021277 (-10150 5900);
DISPLAY INVISIBLE (-10150 5900);
FORCEPROP 0 LAST $SEC 1
J 0
(-10150 5900);
DISPLAY 0.680851 (-10150 5900);
PAINT MONO (-10150 5900);
DISPLAY INVISIBLE (-10150 5900);
FORCEPROP 0 LAST CDS_SEC 1
J 0
(-10150 5900);
DISPLAY 1.021277 (-10150 5900);
DISPLAY INVISIBLE (-10150 5900);
FORCEADD CAPACITOR..2
(-9800 5700);
FORCEPROP 1 LAST VALUE 0.1UF
J 0
(-9750 5750);
DISPLAY 1.212766 (-9750 5750);
PAINT GREEN (-9750 5750);
FORCEPROP 0 LAST VOLTAGE 10V
J 0
(-9750 5850);
DISPLAY 1.021277 (-9750 5850);
FORCEPROP 0 LAST PACKAGE 0402
J 0
(-9750 5950);
DISPLAY 1.021277 (-9750 5950);
FORCEPROP 1 LAST PATH I185
J 0
(-9900 5750);
DISPLAY 1.212766 (-9900 5750);
PAINT GREEN (-9900 5750);
DISPLAY INVISIBLE (-9900 5750);
FORCEPROP 1 LAST TOLERANCE 10%
J 0
(-9950 5800);
DISPLAY 1.212766 (-9950 5800);
PAINT GREEN (-9950 5800);
DISPLAY INVISIBLE (-9950 5800);
FORCEPROP 2 LAST CDS_LIB passive
J 0
(-9800 5700);
DISPLAY INVISIBLE (-9800 5700);
FORCEPROP 1 LAST CDS_LMAN_SYM_OUTLINE -50,0,50,-50
J 0
(-9800 5700);
DISPLAY 0.468085 (-9800 5700);
PAINT GREEN (-9800 5700);
DISPLAY INVISIBLE (-9800 5700);
FORCEPROP 1 LAST CLS_PN G105-0B104-CK
J 0
(-9900 5750);
DISPLAY 1.212766 (-9900 5750);
PAINT GREEN (-9900 5750);
DISPLAY INVISIBLE (-9900 5750);
FORCEPROP 1 LAST $LOCATION C222
J 0
(-9750 5550);
DISPLAY 1.212766 (-9750 5550);
PAINT GREEN (-9750 5550);
FORCEPROP 0 LASTPIN (-9800 5800) $PN 1
R 1
J 0
(-9810 5810);
DISPLAY 0.680851 (-9810 5810);
PAINT MONO (-9810 5810);
FORCEPROP 0 LASTPIN (-9800 5550) $PN 2
R 1
J 2
(-9810 5540);
DISPLAY 0.680851 (-9810 5540);
PAINT MONO (-9810 5540);
FORCEPROP 0 LAST CDS_LOCATION C222
J 0
(-9750 5900);
DISPLAY 1.021277 (-9750 5900);
DISPLAY INVISIBLE (-9750 5900);
FORCEPROP 0 LAST $SEC 1
J 0
(-9750 5900);
DISPLAY 0.680851 (-9750 5900);
PAINT MONO (-9750 5900);
DISPLAY INVISIBLE (-9750 5900);
FORCEPROP 0 LAST CDS_SEC 1
J 0
(-9750 5900);
DISPLAY 1.021277 (-9750 5900);
DISPLAY INVISIBLE (-9750 5900);
FORCEADD CAPACITOR..2
(-9450 5700);
FORCEPROP 1 LAST VALUE 0.1UF
J 0
(-9400 5750);
DISPLAY 1.212766 (-9400 5750);
PAINT GREEN (-9400 5750);
FORCEPROP 0 LAST PACKAGE 0402
J 0
(-9400 5950);
DISPLAY 1.021277 (-9400 5950);
FORCEPROP 0 LAST VOLTAGE 10V
J 0
(-9400 5850);
DISPLAY 1.021277 (-9400 5850);
FORCEPROP 1 LAST PATH I186
J 0
(-9550 5750);
DISPLAY 1.212766 (-9550 5750);
PAINT GREEN (-9550 5750);
DISPLAY INVISIBLE (-9550 5750);
FORCEPROP 1 LAST TOLERANCE 10%
J 0
(-9600 5800);
DISPLAY 1.212766 (-9600 5800);
PAINT GREEN (-9600 5800);
DISPLAY INVISIBLE (-9600 5800);
FORCEPROP 2 LAST CDS_LIB passive
J 0
(-9450 5700);
DISPLAY INVISIBLE (-9450 5700);
FORCEPROP 1 LAST CDS_LMAN_SYM_OUTLINE -50,0,50,-50
J 0
(-9450 5700);
DISPLAY 0.468085 (-9450 5700);
PAINT GREEN (-9450 5700);
DISPLAY INVISIBLE (-9450 5700);
FORCEPROP 1 LAST CLS_PN G105-0B104-CK
J 0
(-9550 5750);
DISPLAY 1.212766 (-9550 5750);
PAINT GREEN (-9550 5750);
DISPLAY INVISIBLE (-9550 5750);
FORCEPROP 1 LAST $LOCATION C109
J 0
(-9400 5550);
DISPLAY 1.212766 (-9400 5550);
PAINT GREEN (-9400 5550);
FORCEPROP 0 LASTPIN (-9450 5800) $PN 1
R 1
J 0
(-9460 5810);
DISPLAY 0.680851 (-9460 5810);
PAINT MONO (-9460 5810);
FORCEPROP 0 LASTPIN (-9450 5550) $PN 2
R 1
J 2
(-9460 5540);
DISPLAY 0.680851 (-9460 5540);
PAINT MONO (-9460 5540);
FORCEPROP 0 LAST CDS_LOCATION C109
J 0
(-9400 5900);
DISPLAY 1.021277 (-9400 5900);
DISPLAY INVISIBLE (-9400 5900);
FORCEPROP 0 LAST $SEC 1
J 0
(-9400 5900);
DISPLAY 0.680851 (-9400 5900);
PAINT MONO (-9400 5900);
DISPLAY INVISIBLE (-9400 5900);
FORCEPROP 0 LAST CDS_SEC 1
J 0
(-9400 5900);
DISPLAY 1.021277 (-9400 5900);
DISPLAY INVISIBLE (-9400 5900);
FORCEADD CAPACITOR..2
(-9100 5700);
FORCEPROP 1 LAST VALUE 0.1UF
J 0
(-9050 5750);
DISPLAY 1.212766 (-9050 5750);
PAINT GREEN (-9050 5750);
FORCEPROP 0 LAST PACKAGE 0402
J 0
(-9050 5950);
DISPLAY 1.021277 (-9050 5950);
FORCEPROP 0 LAST VOLTAGE 10V
J 0
(-9050 5850);
DISPLAY 1.021277 (-9050 5850);
FORCEPROP 1 LAST PATH I187
J 0
(-9200 5750);
DISPLAY 1.212766 (-9200 5750);
PAINT GREEN (-9200 5750);
DISPLAY INVISIBLE (-9200 5750);
FORCEPROP 1 LAST TOLERANCE 10%
J 0
(-9250 5800);
DISPLAY 1.212766 (-9250 5800);
PAINT GREEN (-9250 5800);
DISPLAY INVISIBLE (-9250 5800);
FORCEPROP 2 LAST CDS_LIB passive
J 0
(-9100 5700);
DISPLAY INVISIBLE (-9100 5700);
FORCEPROP 1 LAST CDS_LMAN_SYM_OUTLINE -50,0,50,-50
J 0
(-9100 5700);
DISPLAY 0.468085 (-9100 5700);
PAINT GREEN (-9100 5700);
DISPLAY INVISIBLE (-9100 5700);
FORCEPROP 1 LAST CLS_PN G105-0B104-CK
J 0
(-9200 5750);
DISPLAY 1.212766 (-9200 5750);
PAINT GREEN (-9200 5750);
DISPLAY INVISIBLE (-9200 5750);
FORCEPROP 1 LAST $LOCATION C114
J 0
(-9050 5550);
DISPLAY 1.212766 (-9050 5550);
PAINT GREEN (-9050 5550);
FORCEPROP 0 LASTPIN (-9100 5800) $PN 1
R 1
J 0
(-9110 5810);
DISPLAY 0.680851 (-9110 5810);
PAINT MONO (-9110 5810);
FORCEPROP 0 LASTPIN (-9100 5550) $PN 2
R 1
J 2
(-9110 5540);
DISPLAY 0.680851 (-9110 5540);
PAINT MONO (-9110 5540);
FORCEPROP 0 LAST CDS_LOCATION C114
J 0
(-9050 5900);
DISPLAY 1.021277 (-9050 5900);
DISPLAY INVISIBLE (-9050 5900);
FORCEPROP 0 LAST $SEC 1
J 0
(-9050 5900);
DISPLAY 0.680851 (-9050 5900);
PAINT MONO (-9050 5900);
DISPLAY INVISIBLE (-9050 5900);
FORCEPROP 0 LAST CDS_SEC 1
J 0
(-9050 5900);
DISPLAY 1.021277 (-9050 5900);
DISPLAY INVISIBLE (-9050 5900);
FORCEADD CAPACITOR..2
(-8750 5700);
FORCEPROP 1 LAST VALUE 0.1UF
J 0
(-8700 5750);
DISPLAY 1.212766 (-8700 5750);
PAINT GREEN (-8700 5750);
FORCEPROP 0 LAST VOLTAGE 10V
J 0
(-8700 5850);
DISPLAY 1.021277 (-8700 5850);
FORCEPROP 0 LAST PACKAGE 0402
J 0
(-8700 5950);
DISPLAY 1.021277 (-8700 5950);
FORCEPROP 1 LAST PATH I188
J 0
(-8850 5750);
DISPLAY 1.212766 (-8850 5750);
PAINT GREEN (-8850 5750);
DISPLAY INVISIBLE (-8850 5750);
FORCEPROP 1 LAST TOLERANCE 10%
J 0
(-8900 5800);
DISPLAY 1.212766 (-8900 5800);
PAINT GREEN (-8900 5800);
DISPLAY INVISIBLE (-8900 5800);
FORCEPROP 2 LAST CDS_LIB passive
J 0
(-8750 5700);
DISPLAY INVISIBLE (-8750 5700);
FORCEPROP 1 LAST CDS_LMAN_SYM_OUTLINE -50,0,50,-50
J 0
(-8750 5700);
DISPLAY 0.468085 (-8750 5700);
PAINT GREEN (-8750 5700);
DISPLAY INVISIBLE (-8750 5700);
FORCEPROP 1 LAST CLS_PN G105-0B104-CK
J 0
(-8850 5750);
DISPLAY 1.212766 (-8850 5750);
PAINT GREEN (-8850 5750);
DISPLAY INVISIBLE (-8850 5750);
FORCEPROP 1 LAST $LOCATION C121
J 0
(-8700 5550);
DISPLAY 1.212766 (-8700 5550);
PAINT GREEN (-8700 5550);
FORCEPROP 0 LASTPIN (-8750 5800) $PN 1
R 1
J 0
(-8760 5810);
DISPLAY 0.680851 (-8760 5810);
PAINT MONO (-8760 5810);
FORCEPROP 0 LASTPIN (-8750 5550) $PN 2
R 1
J 2
(-8760 5540);
DISPLAY 0.680851 (-8760 5540);
PAINT MONO (-8760 5540);
FORCEPROP 0 LAST CDS_LOCATION C121
J 0
(-8700 5900);
DISPLAY 1.021277 (-8700 5900);
DISPLAY INVISIBLE (-8700 5900);
FORCEPROP 0 LAST $SEC 1
J 0
(-8700 5900);
DISPLAY 0.680851 (-8700 5900);
PAINT MONO (-8700 5900);
DISPLAY INVISIBLE (-8700 5900);
FORCEPROP 0 LAST CDS_SEC 1
J 0
(-8700 5900);
DISPLAY 1.021277 (-8700 5900);
DISPLAY INVISIBLE (-8700 5900);
FORCEADD CAPACITOR..2
(-8350 5700);
FORCEPROP 1 LAST VALUE 0.1UF
J 0
(-8300 5750);
DISPLAY 1.212766 (-8300 5750);
PAINT GREEN (-8300 5750);
FORCEPROP 0 LAST VOLTAGE 10V
J 0
(-8300 5850);
DISPLAY 1.021277 (-8300 5850);
FORCEPROP 0 LAST PACKAGE 0402
J 0
(-8300 5950);
DISPLAY 1.021277 (-8300 5950);
FORCEPROP 1 LAST PATH I189
J 0
(-8450 5750);
DISPLAY 1.212766 (-8450 5750);
PAINT GREEN (-8450 5750);
DISPLAY INVISIBLE (-8450 5750);
FORCEPROP 1 LAST TOLERANCE 10%
J 0
(-8500 5800);
DISPLAY 1.212766 (-8500 5800);
PAINT GREEN (-8500 5800);
DISPLAY INVISIBLE (-8500 5800);
FORCEPROP 2 LAST CDS_LIB passive
J 0
(-8350 5700);
DISPLAY INVISIBLE (-8350 5700);
FORCEPROP 1 LAST CDS_LMAN_SYM_OUTLINE -50,0,50,-50
J 0
(-8350 5700);
DISPLAY 0.468085 (-8350 5700);
PAINT GREEN (-8350 5700);
DISPLAY INVISIBLE (-8350 5700);
FORCEPROP 1 LAST CLS_PN G105-0B104-CK
J 0
(-8450 5750);
DISPLAY 1.212766 (-8450 5750);
PAINT GREEN (-8450 5750);
DISPLAY INVISIBLE (-8450 5750);
FORCEPROP 1 LAST $LOCATION C129
J 0
(-8300 5550);
DISPLAY 1.212766 (-8300 5550);
PAINT GREEN (-8300 5550);
FORCEPROP 0 LASTPIN (-8350 5800) $PN 1
R 1
J 0
(-8360 5810);
DISPLAY 0.680851 (-8360 5810);
PAINT MONO (-8360 5810);
FORCEPROP 0 LASTPIN (-8350 5550) $PN 2
R 1
J 2
(-8360 5540);
DISPLAY 0.680851 (-8360 5540);
PAINT MONO (-8360 5540);
FORCEPROP 0 LAST CDS_LOCATION C129
J 0
(-8300 5900);
DISPLAY 1.021277 (-8300 5900);
DISPLAY INVISIBLE (-8300 5900);
FORCEPROP 0 LAST $SEC 1
J 0
(-8300 5900);
DISPLAY 0.680851 (-8300 5900);
PAINT MONO (-8300 5900);
DISPLAY INVISIBLE (-8300 5900);
FORCEPROP 0 LAST CDS_SEC 1
J 0
(-8300 5900);
DISPLAY 1.021277 (-8300 5900);
DISPLAY INVISIBLE (-8300 5900);
FORCEADD CAPACITOR..2
(-8000 5700);
FORCEPROP 1 LAST VALUE 0.1UF
J 0
(-7950 5750);
DISPLAY 1.212766 (-7950 5750);
PAINT GREEN (-7950 5750);
FORCEPROP 0 LAST VOLTAGE 10V
J 0
(-7950 5850);
DISPLAY 1.021277 (-7950 5850);
FORCEPROP 0 LAST PACKAGE 0402
J 0
(-7950 5950);
DISPLAY 1.021277 (-7950 5950);
FORCEPROP 1 LAST PATH I190
J 0
(-8100 5750);
DISPLAY 1.212766 (-8100 5750);
PAINT GREEN (-8100 5750);
DISPLAY INVISIBLE (-8100 5750);
FORCEPROP 1 LAST TOLERANCE 10%
J 0
(-8150 5800);
DISPLAY 1.212766 (-8150 5800);
PAINT GREEN (-8150 5800);
DISPLAY INVISIBLE (-8150 5800);
FORCEPROP 1 LAST CDS_LMAN_SYM_OUTLINE -50,0,50,-50
J 0
(-8000 5700);
DISPLAY 0.468085 (-8000 5700);
PAINT GREEN (-8000 5700);
DISPLAY INVISIBLE (-8000 5700);
FORCEPROP 2 LAST CDS_LIB passive
J 0
(-8000 5700);
DISPLAY INVISIBLE (-8000 5700);
FORCEPROP 1 LAST CLS_PN G105-0B104-CK
J 0
(-8100 5750);
DISPLAY 1.212766 (-8100 5750);
PAINT GREEN (-8100 5750);
DISPLAY INVISIBLE (-8100 5750);
FORCEPROP 1 LAST $LOCATION C133
J 0
(-7950 5550);
DISPLAY 1.212766 (-7950 5550);
PAINT GREEN (-7950 5550);
FORCEPROP 0 LASTPIN (-8000 5800) $PN 1
R 1
J 0
(-8010 5810);
DISPLAY 0.680851 (-8010 5810);
PAINT MONO (-8010 5810);
FORCEPROP 0 LASTPIN (-8000 5550) $PN 2
R 1
J 2
(-8010 5540);
DISPLAY 0.680851 (-8010 5540);
PAINT MONO (-8010 5540);
FORCEPROP 0 LAST CDS_LOCATION C133
J 0
(-7950 5900);
DISPLAY 1.021277 (-7950 5900);
DISPLAY INVISIBLE (-7950 5900);
FORCEPROP 0 LAST $SEC 1
J 0
(-7950 5900);
DISPLAY 0.680851 (-7950 5900);
PAINT MONO (-7950 5900);
DISPLAY INVISIBLE (-7950 5900);
FORCEPROP 0 LAST CDS_SEC 1
J 0
(-7950 5900);
DISPLAY 1.021277 (-7950 5900);
DISPLAY INVISIBLE (-7950 5900);
FORCEADD CAPACITOR..2
(-7600 5700);
FORCEPROP 1 LAST VALUE 0.1UF
J 0
(-7550 5750);
DISPLAY 1.212766 (-7550 5750);
PAINT GREEN (-7550 5750);
FORCEPROP 0 LAST VOLTAGE 10V
J 0
(-7550 5850);
DISPLAY 1.021277 (-7550 5850);
FORCEPROP 0 LAST PACKAGE 0402
J 0
(-7550 5950);
DISPLAY 1.021277 (-7550 5950);
FORCEPROP 1 LAST PATH I191
J 0
(-7700 5750);
DISPLAY 1.212766 (-7700 5750);
PAINT GREEN (-7700 5750);
DISPLAY INVISIBLE (-7700 5750);
FORCEPROP 1 LAST TOLERANCE 10%
J 0
(-7750 5800);
DISPLAY 1.212766 (-7750 5800);
PAINT GREEN (-7750 5800);
DISPLAY INVISIBLE (-7750 5800);
FORCEPROP 1 LAST CDS_LMAN_SYM_OUTLINE -50,0,50,-50
J 0
(-7600 5700);
DISPLAY 0.468085 (-7600 5700);
PAINT GREEN (-7600 5700);
DISPLAY INVISIBLE (-7600 5700);
FORCEPROP 2 LAST CDS_LIB passive
J 0
(-7600 5700);
DISPLAY INVISIBLE (-7600 5700);
FORCEPROP 1 LAST CLS_PN G105-0B104-CK
J 0
(-7700 5750);
DISPLAY 1.212766 (-7700 5750);
PAINT GREEN (-7700 5750);
DISPLAY INVISIBLE (-7700 5750);
FORCEPROP 1 LAST $LOCATION C141
J 0
(-7550 5550);
DISPLAY 1.212766 (-7550 5550);
PAINT GREEN (-7550 5550);
FORCEPROP 0 LASTPIN (-7600 5800) $PN 1
R 1
J 0
(-7610 5810);
DISPLAY 0.680851 (-7610 5810);
PAINT MONO (-7610 5810);
FORCEPROP 0 LASTPIN (-7600 5550) $PN 2
R 1
J 2
(-7610 5540);
DISPLAY 0.680851 (-7610 5540);
PAINT MONO (-7610 5540);
FORCEPROP 0 LAST CDS_LOCATION C141
J 0
(-7550 5900);
DISPLAY 1.021277 (-7550 5900);
DISPLAY INVISIBLE (-7550 5900);
FORCEPROP 0 LAST $SEC 1
J 0
(-7550 5900);
DISPLAY 0.680851 (-7550 5900);
PAINT MONO (-7550 5900);
DISPLAY INVISIBLE (-7550 5900);
FORCEPROP 0 LAST CDS_SEC 1
J 0
(-7550 5900);
DISPLAY 1.021277 (-7550 5900);
DISPLAY INVISIBLE (-7550 5900);
FORCEADD CAPACITOR..2
(-7200 5700);
FORCEPROP 1 LAST VALUE 0.1UF
J 0
(-7150 5750);
DISPLAY 1.212766 (-7150 5750);
PAINT GREEN (-7150 5750);
FORCEPROP 0 LAST VOLTAGE 10V
J 0
(-7150 5850);
DISPLAY 1.021277 (-7150 5850);
FORCEPROP 0 LAST PACKAGE 0402
J 0
(-7150 5950);
DISPLAY 1.021277 (-7150 5950);
FORCEPROP 1 LAST PATH I192
J 0
(-7300 5750);
DISPLAY 1.212766 (-7300 5750);
PAINT GREEN (-7300 5750);
DISPLAY INVISIBLE (-7300 5750);
FORCEPROP 1 LAST TOLERANCE 10%
J 0
(-7350 5800);
DISPLAY 1.212766 (-7350 5800);
PAINT GREEN (-7350 5800);
DISPLAY INVISIBLE (-7350 5800);
FORCEPROP 1 LAST CLS_PN G105-0B104-CK
J 0
(-7300 5750);
DISPLAY 1.212766 (-7300 5750);
PAINT GREEN (-7300 5750);
DISPLAY INVISIBLE (-7300 5750);
FORCEPROP 2 LAST CDS_LIB passive
J 0
(-7200 5700);
DISPLAY INVISIBLE (-7200 5700);
FORCEPROP 1 LAST CDS_LMAN_SYM_OUTLINE -50,0,50,-50
J 0
(-7200 5700);
DISPLAY 0.468085 (-7200 5700);
PAINT GREEN (-7200 5700);
DISPLAY INVISIBLE (-7200 5700);
FORCEPROP 1 LAST $LOCATION C147
J 0
(-7150 5550);
DISPLAY 1.212766 (-7150 5550);
PAINT GREEN (-7150 5550);
FORCEPROP 0 LASTPIN (-7200 5800) $PN 1
R 1
J 0
(-7210 5810);
DISPLAY 0.680851 (-7210 5810);
PAINT MONO (-7210 5810);
FORCEPROP 0 LASTPIN (-7200 5550) $PN 2
R 1
J 2
(-7210 5540);
DISPLAY 0.680851 (-7210 5540);
PAINT MONO (-7210 5540);
FORCEPROP 0 LAST CDS_LOCATION C147
J 0
(-7150 5900);
DISPLAY 1.021277 (-7150 5900);
DISPLAY INVISIBLE (-7150 5900);
FORCEPROP 0 LAST $SEC 1
J 0
(-7150 5900);
DISPLAY 0.680851 (-7150 5900);
PAINT MONO (-7150 5900);
DISPLAY INVISIBLE (-7150 5900);
FORCEPROP 0 LAST CDS_SEC 1
J 0
(-7150 5900);
DISPLAY 1.021277 (-7150 5900);
DISPLAY INVISIBLE (-7150 5900);
FORCEADD CAPACITOR..2
(-6850 5700);
FORCEPROP 1 LAST VALUE 0.1UF
J 0
(-6800 5750);
DISPLAY 1.212766 (-6800 5750);
PAINT GREEN (-6800 5750);
FORCEPROP 0 LAST VOLTAGE 10V
J 0
(-6800 5850);
DISPLAY 1.021277 (-6800 5850);
FORCEPROP 0 LAST PACKAGE 0402
J 0
(-6800 5950);
DISPLAY 1.021277 (-6800 5950);
FORCEPROP 1 LAST PATH I193
J 0
(-6950 5750);
DISPLAY 1.212766 (-6950 5750);
PAINT GREEN (-6950 5750);
DISPLAY INVISIBLE (-6950 5750);
FORCEPROP 1 LAST TOLERANCE 10%
J 0
(-7000 5800);
DISPLAY 1.212766 (-7000 5800);
PAINT GREEN (-7000 5800);
DISPLAY INVISIBLE (-7000 5800);
FORCEPROP 1 LAST CDS_LMAN_SYM_OUTLINE -50,0,50,-50
J 0
(-6850 5700);
DISPLAY 0.468085 (-6850 5700);
PAINT GREEN (-6850 5700);
DISPLAY INVISIBLE (-6850 5700);
FORCEPROP 2 LAST CDS_LIB passive
J 0
(-6850 5700);
DISPLAY INVISIBLE (-6850 5700);
FORCEPROP 1 LAST CLS_PN G105-0B104-CK
J 0
(-6950 5750);
DISPLAY 1.212766 (-6950 5750);
PAINT GREEN (-6950 5750);
DISPLAY INVISIBLE (-6950 5750);
FORCEPROP 1 LAST $LOCATION C152
J 0
(-6800 5550);
DISPLAY 1.212766 (-6800 5550);
PAINT GREEN (-6800 5550);
FORCEPROP 0 LASTPIN (-6850 5800) $PN 1
R 1
J 0
(-6860 5810);
DISPLAY 0.680851 (-6860 5810);
PAINT MONO (-6860 5810);
FORCEPROP 0 LASTPIN (-6850 5550) $PN 2
R 1
J 2
(-6860 5540);
DISPLAY 0.680851 (-6860 5540);
PAINT MONO (-6860 5540);
FORCEPROP 0 LAST CDS_LOCATION C152
J 0
(-6800 5900);
DISPLAY 1.021277 (-6800 5900);
DISPLAY INVISIBLE (-6800 5900);
FORCEPROP 0 LAST $SEC 1
J 0
(-6800 5900);
DISPLAY 0.680851 (-6800 5900);
PAINT MONO (-6800 5900);
DISPLAY INVISIBLE (-6800 5900);
FORCEPROP 0 LAST CDS_SEC 1
J 0
(-6800 5900);
DISPLAY 1.021277 (-6800 5900);
DISPLAY INVISIBLE (-6800 5900);
FORCEADD CAPACITOR..2
(-6500 5700);
FORCEPROP 0 LAST PACKAGE 0402
J 0
(-6450 5950);
DISPLAY 1.021277 (-6450 5950);
FORCEPROP 1 LAST VALUE 0.1UF
J 0
(-6450 5750);
DISPLAY 1.212766 (-6450 5750);
PAINT GREEN (-6450 5750);
FORCEPROP 0 LAST VOLTAGE 10V
J 0
(-6450 5850);
DISPLAY 1.021277 (-6450 5850);
FORCEPROP 1 LAST PATH I194
J 0
(-6600 5750);
DISPLAY 1.212766 (-6600 5750);
PAINT GREEN (-6600 5750);
DISPLAY INVISIBLE (-6600 5750);
FORCEPROP 1 LAST TOLERANCE 10%
J 0
(-6650 5800);
DISPLAY 1.212766 (-6650 5800);
PAINT GREEN (-6650 5800);
DISPLAY INVISIBLE (-6650 5800);
FORCEPROP 1 LAST CDS_LMAN_SYM_OUTLINE -50,0,50,-50
J 0
(-6500 5700);
DISPLAY 0.468085 (-6500 5700);
PAINT GREEN (-6500 5700);
DISPLAY INVISIBLE (-6500 5700);
FORCEPROP 2 LAST CDS_LIB passive
J 0
(-6500 5700);
DISPLAY INVISIBLE (-6500 5700);
FORCEPROP 1 LAST CLS_PN G105-0B104-CK
J 0
(-6600 5750);
DISPLAY 1.212766 (-6600 5750);
PAINT GREEN (-6600 5750);
DISPLAY INVISIBLE (-6600 5750);
FORCEPROP 1 LAST $LOCATION C156
J 0
(-6450 5550);
DISPLAY 1.212766 (-6450 5550);
PAINT GREEN (-6450 5550);
FORCEPROP 0 LASTPIN (-6500 5800) $PN 1
R 1
J 0
(-6510 5810);
DISPLAY 0.680851 (-6510 5810);
PAINT MONO (-6510 5810);
FORCEPROP 0 LASTPIN (-6500 5550) $PN 2
R 1
J 2
(-6510 5540);
DISPLAY 0.680851 (-6510 5540);
PAINT MONO (-6510 5540);
FORCEPROP 0 LAST CDS_LOCATION C156
J 0
(-6450 5900);
DISPLAY 1.021277 (-6450 5900);
DISPLAY INVISIBLE (-6450 5900);
FORCEPROP 0 LAST $SEC 1
J 0
(-6450 5900);
DISPLAY 0.680851 (-6450 5900);
PAINT MONO (-6450 5900);
DISPLAY INVISIBLE (-6450 5900);
FORCEPROP 0 LAST CDS_SEC 1
J 0
(-6450 5900);
DISPLAY 1.021277 (-6450 5900);
DISPLAY INVISIBLE (-6450 5900);
FORCEADD CAPACITOR..2
(-6150 5700);
FORCEPROP 0 LAST PACKAGE 0402
J 0
(-6100 5950);
DISPLAY 1.021277 (-6100 5950);
FORCEPROP 1 LAST VALUE 0.1UF
J 0
(-6100 5750);
DISPLAY 1.212766 (-6100 5750);
PAINT GREEN (-6100 5750);
FORCEPROP 0 LAST VOLTAGE 10V
J 0
(-6100 5850);
DISPLAY 1.021277 (-6100 5850);
FORCEPROP 1 LAST PATH I195
J 0
(-6250 5750);
DISPLAY 1.212766 (-6250 5750);
PAINT GREEN (-6250 5750);
DISPLAY INVISIBLE (-6250 5750);
FORCEPROP 1 LAST TOLERANCE 10%
J 0
(-6300 5800);
DISPLAY 1.212766 (-6300 5800);
PAINT GREEN (-6300 5800);
DISPLAY INVISIBLE (-6300 5800);
FORCEPROP 1 LAST CDS_LMAN_SYM_OUTLINE -50,0,50,-50
J 0
(-6150 5700);
DISPLAY 0.468085 (-6150 5700);
PAINT GREEN (-6150 5700);
DISPLAY INVISIBLE (-6150 5700);
FORCEPROP 2 LAST CDS_LIB passive
J 0
(-6150 5700);
DISPLAY INVISIBLE (-6150 5700);
FORCEPROP 1 LAST CLS_PN G105-0B104-CK
J 0
(-6250 5750);
DISPLAY 1.212766 (-6250 5750);
PAINT GREEN (-6250 5750);
DISPLAY INVISIBLE (-6250 5750);
FORCEPROP 1 LAST $LOCATION C161
J 0
(-6100 5550);
DISPLAY 1.212766 (-6100 5550);
PAINT GREEN (-6100 5550);
FORCEPROP 0 LASTPIN (-6150 5800) $PN 1
R 1
J 0
(-6160 5810);
DISPLAY 0.680851 (-6160 5810);
PAINT MONO (-6160 5810);
FORCEPROP 0 LASTPIN (-6150 5550) $PN 2
R 1
J 2
(-6160 5540);
DISPLAY 0.680851 (-6160 5540);
PAINT MONO (-6160 5540);
FORCEPROP 0 LAST CDS_LOCATION C161
J 0
(-6100 5900);
DISPLAY 1.021277 (-6100 5900);
DISPLAY INVISIBLE (-6100 5900);
FORCEPROP 0 LAST $SEC 1
J 0
(-6100 5900);
DISPLAY 0.680851 (-6100 5900);
PAINT MONO (-6100 5900);
DISPLAY INVISIBLE (-6100 5900);
FORCEPROP 0 LAST CDS_SEC 1
J 0
(-6100 5900);
DISPLAY 1.021277 (-6100 5900);
DISPLAY INVISIBLE (-6100 5900);
FORCEADD CAPACITOR..2
(-5750 5700);
FORCEPROP 1 LAST VALUE 0.1UF
J 0
(-5700 5750);
DISPLAY 1.212766 (-5700 5750);
PAINT GREEN (-5700 5750);
FORCEPROP 0 LAST VOLTAGE 10V
J 0
(-5700 5850);
DISPLAY 1.021277 (-5700 5850);
FORCEPROP 0 LAST PACKAGE 0402
J 0
(-5700 5950);
DISPLAY 1.021277 (-5700 5950);
FORCEPROP 1 LAST PATH I196
J 0
(-5850 5750);
DISPLAY 1.212766 (-5850 5750);
PAINT GREEN (-5850 5750);
DISPLAY INVISIBLE (-5850 5750);
FORCEPROP 1 LAST TOLERANCE 10%
J 0
(-5900 5800);
DISPLAY 1.212766 (-5900 5800);
PAINT GREEN (-5900 5800);
DISPLAY INVISIBLE (-5900 5800);
FORCEPROP 1 LAST CDS_LMAN_SYM_OUTLINE -50,0,50,-50
J 0
(-5750 5700);
DISPLAY 0.468085 (-5750 5700);
PAINT GREEN (-5750 5700);
DISPLAY INVISIBLE (-5750 5700);
FORCEPROP 2 LAST CDS_LIB passive
J 0
(-5750 5700);
DISPLAY INVISIBLE (-5750 5700);
FORCEPROP 1 LAST CLS_PN G105-0B104-CK
J 0
(-5850 5750);
DISPLAY 1.212766 (-5850 5750);
PAINT GREEN (-5850 5750);
DISPLAY INVISIBLE (-5850 5750);
FORCEPROP 1 LAST $LOCATION C166
J 0
(-5700 5550);
DISPLAY 1.212766 (-5700 5550);
PAINT GREEN (-5700 5550);
FORCEPROP 0 LASTPIN (-5750 5800) $PN 1
R 1
J 0
(-5760 5810);
DISPLAY 0.680851 (-5760 5810);
PAINT MONO (-5760 5810);
FORCEPROP 0 LASTPIN (-5750 5550) $PN 2
R 1
J 2
(-5760 5540);
DISPLAY 0.680851 (-5760 5540);
PAINT MONO (-5760 5540);
FORCEPROP 0 LAST CDS_LOCATION C166
J 0
(-5700 5900);
DISPLAY 1.021277 (-5700 5900);
DISPLAY INVISIBLE (-5700 5900);
FORCEPROP 0 LAST $SEC 1
J 0
(-5700 5900);
DISPLAY 0.680851 (-5700 5900);
PAINT MONO (-5700 5900);
DISPLAY INVISIBLE (-5700 5900);
FORCEPROP 0 LAST CDS_SEC 1
J 0
(-5700 5900);
DISPLAY 1.021277 (-5700 5900);
DISPLAY INVISIBLE (-5700 5900);
FORCEADD CAPACITOR..2
(-5400 5700);
FORCEPROP 1 LAST VALUE 0.1UF
J 0
(-5350 5750);
DISPLAY 1.212766 (-5350 5750);
PAINT GREEN (-5350 5750);
FORCEPROP 0 LAST VOLTAGE 10V
J 0
(-5350 5850);
DISPLAY 1.021277 (-5350 5850);
FORCEPROP 0 LAST PACKAGE 0402
J 0
(-5350 5950);
DISPLAY 1.021277 (-5350 5950);
FORCEPROP 1 LAST PATH I197
J 0
(-5500 5750);
DISPLAY 1.212766 (-5500 5750);
PAINT GREEN (-5500 5750);
DISPLAY INVISIBLE (-5500 5750);
FORCEPROP 1 LAST TOLERANCE 10%
J 0
(-5550 5800);
DISPLAY 1.212766 (-5550 5800);
PAINT GREEN (-5550 5800);
DISPLAY INVISIBLE (-5550 5800);
FORCEPROP 1 LAST CDS_LMAN_SYM_OUTLINE -50,0,50,-50
J 0
(-5400 5700);
DISPLAY 0.468085 (-5400 5700);
PAINT GREEN (-5400 5700);
DISPLAY INVISIBLE (-5400 5700);
FORCEPROP 2 LAST CDS_LIB passive
J 0
(-5400 5700);
DISPLAY INVISIBLE (-5400 5700);
FORCEPROP 1 LAST CLS_PN G105-0B104-CK
J 0
(-5500 5750);
DISPLAY 1.212766 (-5500 5750);
PAINT GREEN (-5500 5750);
DISPLAY INVISIBLE (-5500 5750);
FORCEPROP 1 LAST $LOCATION C169
J 0
(-5350 5550);
DISPLAY 1.212766 (-5350 5550);
PAINT GREEN (-5350 5550);
FORCEPROP 0 LASTPIN (-5400 5800) $PN 1
R 1
J 0
(-5410 5810);
DISPLAY 0.680851 (-5410 5810);
PAINT MONO (-5410 5810);
FORCEPROP 0 LASTPIN (-5400 5550) $PN 2
R 1
J 2
(-5410 5540);
DISPLAY 0.680851 (-5410 5540);
PAINT MONO (-5410 5540);
FORCEPROP 0 LAST CDS_LOCATION C169
J 0
(-5350 5900);
DISPLAY 1.021277 (-5350 5900);
DISPLAY INVISIBLE (-5350 5900);
FORCEPROP 0 LAST $SEC 1
J 0
(-5350 5900);
DISPLAY 0.680851 (-5350 5900);
PAINT MONO (-5350 5900);
DISPLAY INVISIBLE (-5350 5900);
FORCEPROP 0 LAST CDS_SEC 1
J 0
(-5350 5900);
DISPLAY 1.021277 (-5350 5900);
DISPLAY INVISIBLE (-5350 5900);
FORCEADD CAPACITOR..2
(-5000 5700);
FORCEPROP 1 LAST VALUE 0.1UF
J 0
(-4950 5750);
DISPLAY 1.212766 (-4950 5750);
PAINT GREEN (-4950 5750);
FORCEPROP 0 LAST VOLTAGE 10V
J 0
(-4950 5850);
DISPLAY 1.021277 (-4950 5850);
FORCEPROP 0 LAST PACKAGE 0402
J 0
(-4950 5950);
DISPLAY 1.021277 (-4950 5950);
FORCEPROP 1 LAST PATH I198
J 0
(-5100 5750);
DISPLAY 1.212766 (-5100 5750);
PAINT GREEN (-5100 5750);
DISPLAY INVISIBLE (-5100 5750);
FORCEPROP 1 LAST TOLERANCE 10%
J 0
(-5150 5800);
DISPLAY 1.212766 (-5150 5800);
PAINT GREEN (-5150 5800);
DISPLAY INVISIBLE (-5150 5800);
FORCEPROP 2 LAST CDS_LIB passive
J 0
(-5000 5700);
DISPLAY INVISIBLE (-5000 5700);
FORCEPROP 1 LAST CDS_LMAN_SYM_OUTLINE -50,0,50,-50
J 0
(-5000 5700);
DISPLAY 0.468085 (-5000 5700);
PAINT GREEN (-5000 5700);
DISPLAY INVISIBLE (-5000 5700);
FORCEPROP 1 LAST CLS_PN G105-0B104-CK
J 0
(-5100 5750);
DISPLAY 1.212766 (-5100 5750);
PAINT GREEN (-5100 5750);
DISPLAY INVISIBLE (-5100 5750);
FORCEPROP 1 LAST $LOCATION C171
J 0
(-4950 5550);
DISPLAY 1.212766 (-4950 5550);
PAINT GREEN (-4950 5550);
FORCEPROP 0 LASTPIN (-5000 5800) $PN 1
R 1
J 0
(-5010 5810);
DISPLAY 0.680851 (-5010 5810);
PAINT MONO (-5010 5810);
FORCEPROP 0 LASTPIN (-5000 5550) $PN 2
R 1
J 2
(-5010 5540);
DISPLAY 0.680851 (-5010 5540);
PAINT MONO (-5010 5540);
FORCEPROP 0 LAST CDS_LOCATION C171
J 0
(-4950 5900);
DISPLAY 1.021277 (-4950 5900);
DISPLAY INVISIBLE (-4950 5900);
FORCEPROP 0 LAST $SEC 1
J 0
(-4950 5900);
DISPLAY 0.680851 (-4950 5900);
PAINT MONO (-4950 5900);
DISPLAY INVISIBLE (-4950 5900);
FORCEPROP 0 LAST CDS_SEC 1
J 0
(-4950 5900);
DISPLAY 1.021277 (-4950 5900);
DISPLAY INVISIBLE (-4950 5900);
FORCEADD CAPACITOR..2
(-10950 7150);
FORCEPROP 1 LAST VALUE 0.1UF
J 0
(-10900 7200);
DISPLAY 1.212766 (-10900 7200);
PAINT GREEN (-10900 7200);
FORCEPROP 0 LAST VOLTAGE 10V
J 0
(-10900 7300);
DISPLAY 1.021277 (-10900 7300);
FORCEPROP 0 LAST PACKAGE 0402
J 0
(-10900 7400);
DISPLAY 1.021277 (-10900 7400);
FORCEPROP 1 LAST PATH I199
J 0
(-11050 7200);
DISPLAY 1.212766 (-11050 7200);
PAINT GREEN (-11050 7200);
DISPLAY INVISIBLE (-11050 7200);
FORCEPROP 1 LAST TOLERANCE 10%
J 0
(-11100 7250);
DISPLAY 1.212766 (-11100 7250);
PAINT GREEN (-11100 7250);
DISPLAY INVISIBLE (-11100 7250);
FORCEPROP 1 LAST CDS_LMAN_SYM_OUTLINE -50,0,50,-50
J 0
(-10950 7150);
DISPLAY 0.468085 (-10950 7150);
PAINT GREEN (-10950 7150);
DISPLAY INVISIBLE (-10950 7150);
FORCEPROP 2 LAST CDS_LIB passive
J 0
(-10950 7150);
DISPLAY INVISIBLE (-10950 7150);
FORCEPROP 1 LAST CLS_PN G105-0B104-CK
J 0
(-11050 7200);
DISPLAY 1.212766 (-11050 7200);
PAINT GREEN (-11050 7200);
DISPLAY INVISIBLE (-11050 7200);
FORCEPROP 1 LAST $LOCATION C200
J 0
(-10900 7000);
DISPLAY 1.212766 (-10900 7000);
PAINT GREEN (-10900 7000);
FORCEPROP 0 LASTPIN (-10950 7250) $PN 1
R 1
J 0
(-10960 7260);
DISPLAY 0.680851 (-10960 7260);
PAINT MONO (-10960 7260);
FORCEPROP 0 LASTPIN (-10950 7000) $PN 2
R 1
J 2
(-10960 6990);
DISPLAY 0.680851 (-10960 6990);
PAINT MONO (-10960 6990);
FORCEPROP 0 LAST CDS_LOCATION C200
J 0
(-10900 7350);
DISPLAY 1.021277 (-10900 7350);
DISPLAY INVISIBLE (-10900 7350);
FORCEPROP 0 LAST $SEC 1
J 0
(-10900 7350);
DISPLAY 0.680851 (-10900 7350);
PAINT MONO (-10900 7350);
DISPLAY INVISIBLE (-10900 7350);
FORCEPROP 0 LAST CDS_SEC 1
J 0
(-10900 7350);
DISPLAY 1.021277 (-10900 7350);
DISPLAY INVISIBLE (-10900 7350);
FORCEADD CAPACITOR..2
(-10600 7150);
FORCEPROP 1 LAST VALUE 0.1UF
J 0
(-10550 7200);
DISPLAY 1.212766 (-10550 7200);
PAINT GREEN (-10550 7200);
FORCEPROP 0 LAST VOLTAGE 10V
J 0
(-10550 7300);
DISPLAY 1.021277 (-10550 7300);
FORCEPROP 0 LAST PACKAGE 0402
J 0
(-10550 7400);
DISPLAY 1.021277 (-10550 7400);
FORCEPROP 1 LAST PATH I200
J 0
(-10700 7200);
DISPLAY 1.212766 (-10700 7200);
PAINT GREEN (-10700 7200);
DISPLAY INVISIBLE (-10700 7200);
FORCEPROP 1 LAST TOLERANCE 10%
J 0
(-10750 7250);
DISPLAY 1.212766 (-10750 7250);
PAINT GREEN (-10750 7250);
DISPLAY INVISIBLE (-10750 7250);
FORCEPROP 1 LAST CDS_LMAN_SYM_OUTLINE -50,0,50,-50
J 0
(-10600 7150);
DISPLAY 0.468085 (-10600 7150);
PAINT GREEN (-10600 7150);
DISPLAY INVISIBLE (-10600 7150);
FORCEPROP 2 LAST CDS_LIB passive
J 0
(-10600 7150);
DISPLAY INVISIBLE (-10600 7150);
FORCEPROP 1 LAST CLS_PN G105-0B104-CK
J 0
(-10700 7200);
DISPLAY 1.212766 (-10700 7200);
PAINT GREEN (-10700 7200);
DISPLAY INVISIBLE (-10700 7200);
FORCEPROP 1 LAST $LOCATION C206
J 0
(-10550 7000);
DISPLAY 1.212766 (-10550 7000);
PAINT GREEN (-10550 7000);
FORCEPROP 0 LASTPIN (-10600 7250) $PN 1
R 1
J 0
(-10610 7260);
DISPLAY 0.680851 (-10610 7260);
PAINT MONO (-10610 7260);
FORCEPROP 0 LASTPIN (-10600 7000) $PN 2
R 1
J 2
(-10610 6990);
DISPLAY 0.680851 (-10610 6990);
PAINT MONO (-10610 6990);
FORCEPROP 0 LAST CDS_LOCATION C206
J 0
(-10550 7350);
DISPLAY 1.021277 (-10550 7350);
DISPLAY INVISIBLE (-10550 7350);
FORCEPROP 0 LAST $SEC 1
J 0
(-10550 7350);
DISPLAY 0.680851 (-10550 7350);
PAINT MONO (-10550 7350);
DISPLAY INVISIBLE (-10550 7350);
FORCEPROP 0 LAST CDS_SEC 1
J 0
(-10550 7350);
DISPLAY 1.021277 (-10550 7350);
DISPLAY INVISIBLE (-10550 7350);
FORCEADD CAPACITOR..2
(-10250 7150);
FORCEPROP 1 LAST VALUE 0.1UF
J 0
(-10200 7200);
DISPLAY 1.212766 (-10200 7200);
PAINT GREEN (-10200 7200);
FORCEPROP 0 LAST VOLTAGE 10V
J 0
(-10200 7300);
DISPLAY 1.021277 (-10200 7300);
FORCEPROP 0 LAST PACKAGE 0402
J 0
(-10200 7400);
DISPLAY 1.021277 (-10200 7400);
FORCEPROP 1 LAST PATH I201
J 0
(-10350 7200);
DISPLAY 1.212766 (-10350 7200);
PAINT GREEN (-10350 7200);
DISPLAY INVISIBLE (-10350 7200);
FORCEPROP 1 LAST TOLERANCE 10%
J 0
(-10400 7250);
DISPLAY 1.212766 (-10400 7250);
PAINT GREEN (-10400 7250);
DISPLAY INVISIBLE (-10400 7250);
FORCEPROP 1 LAST CDS_LMAN_SYM_OUTLINE -50,0,50,-50
J 0
(-10250 7150);
DISPLAY 0.468085 (-10250 7150);
PAINT GREEN (-10250 7150);
DISPLAY INVISIBLE (-10250 7150);
FORCEPROP 2 LAST CDS_LIB passive
J 0
(-10250 7150);
DISPLAY INVISIBLE (-10250 7150);
FORCEPROP 1 LAST CLS_PN G105-0B104-CK
J 0
(-10350 7200);
DISPLAY 1.212766 (-10350 7200);
PAINT GREEN (-10350 7200);
DISPLAY INVISIBLE (-10350 7200);
FORCEPROP 1 LAST $LOCATION C212
J 0
(-10200 7000);
DISPLAY 1.212766 (-10200 7000);
PAINT GREEN (-10200 7000);
FORCEPROP 0 LASTPIN (-10250 7250) $PN 1
R 1
J 0
(-10260 7260);
DISPLAY 0.680851 (-10260 7260);
PAINT MONO (-10260 7260);
FORCEPROP 0 LASTPIN (-10250 7000) $PN 2
R 1
J 2
(-10260 6990);
DISPLAY 0.680851 (-10260 6990);
PAINT MONO (-10260 6990);
FORCEPROP 0 LAST CDS_LOCATION C212
J 0
(-10200 7350);
DISPLAY 1.021277 (-10200 7350);
DISPLAY INVISIBLE (-10200 7350);
FORCEPROP 0 LAST $SEC 1
J 0
(-10200 7350);
DISPLAY 0.680851 (-10200 7350);
PAINT MONO (-10200 7350);
DISPLAY INVISIBLE (-10200 7350);
FORCEPROP 0 LAST CDS_SEC 1
J 0
(-10200 7350);
DISPLAY 1.021277 (-10200 7350);
DISPLAY INVISIBLE (-10200 7350);
FORCEADD CAPACITOR..2
(-9900 7150);
FORCEPROP 1 LAST VALUE 0.1UF
J 0
(-9850 7200);
DISPLAY 1.212766 (-9850 7200);
PAINT GREEN (-9850 7200);
FORCEPROP 0 LAST VOLTAGE 10V
J 0
(-9850 7300);
DISPLAY 1.021277 (-9850 7300);
FORCEPROP 0 LAST PACKAGE 0402
J 0
(-9850 7400);
DISPLAY 1.021277 (-9850 7400);
FORCEPROP 1 LAST PATH I202
J 0
(-10000 7200);
DISPLAY 1.212766 (-10000 7200);
PAINT GREEN (-10000 7200);
DISPLAY INVISIBLE (-10000 7200);
FORCEPROP 1 LAST TOLERANCE 10%
J 0
(-10050 7250);
DISPLAY 1.212766 (-10050 7250);
PAINT GREEN (-10050 7250);
DISPLAY INVISIBLE (-10050 7250);
FORCEPROP 1 LAST CDS_LMAN_SYM_OUTLINE -50,0,50,-50
J 0
(-9900 7150);
DISPLAY 0.468085 (-9900 7150);
PAINT GREEN (-9900 7150);
DISPLAY INVISIBLE (-9900 7150);
FORCEPROP 2 LAST CDS_LIB passive
J 0
(-9900 7150);
DISPLAY INVISIBLE (-9900 7150);
FORCEPROP 1 LAST CLS_PN G105-0B104-CK
J 0
(-10000 7200);
DISPLAY 1.212766 (-10000 7200);
PAINT GREEN (-10000 7200);
DISPLAY INVISIBLE (-10000 7200);
FORCEPROP 1 LAST $LOCATION C219
J 0
(-9850 7000);
DISPLAY 1.212766 (-9850 7000);
PAINT GREEN (-9850 7000);
FORCEPROP 0 LASTPIN (-9900 7250) $PN 1
R 1
J 0
(-9910 7260);
DISPLAY 0.680851 (-9910 7260);
PAINT MONO (-9910 7260);
FORCEPROP 0 LASTPIN (-9900 7000) $PN 2
R 1
J 2
(-9910 6990);
DISPLAY 0.680851 (-9910 6990);
PAINT MONO (-9910 6990);
FORCEPROP 0 LAST CDS_LOCATION C219
J 0
(-9850 7350);
DISPLAY 1.021277 (-9850 7350);
DISPLAY INVISIBLE (-9850 7350);
FORCEPROP 0 LAST $SEC 1
J 0
(-9850 7350);
DISPLAY 0.680851 (-9850 7350);
PAINT MONO (-9850 7350);
DISPLAY INVISIBLE (-9850 7350);
FORCEPROP 0 LAST CDS_SEC 1
J 0
(-9850 7350);
DISPLAY 1.021277 (-9850 7350);
DISPLAY INVISIBLE (-9850 7350);
FORCEADD CAPACITOR..2
(-9500 7150);
FORCEPROP 1 LAST VALUE 0.1UF
J 0
(-9450 7200);
DISPLAY 1.212766 (-9450 7200);
PAINT GREEN (-9450 7200);
FORCEPROP 0 LAST VOLTAGE 10V
J 0
(-9450 7300);
DISPLAY 1.021277 (-9450 7300);
FORCEPROP 0 LAST PACKAGE 0402
J 0
(-9450 7400);
DISPLAY 1.021277 (-9450 7400);
FORCEPROP 1 LAST PATH I203
J 0
(-9600 7200);
DISPLAY 1.212766 (-9600 7200);
PAINT GREEN (-9600 7200);
DISPLAY INVISIBLE (-9600 7200);
FORCEPROP 1 LAST TOLERANCE 10%
J 0
(-9650 7250);
DISPLAY 1.212766 (-9650 7250);
PAINT GREEN (-9650 7250);
DISPLAY INVISIBLE (-9650 7250);
FORCEPROP 1 LAST CDS_LMAN_SYM_OUTLINE -50,0,50,-50
J 0
(-9500 7150);
DISPLAY 0.468085 (-9500 7150);
PAINT GREEN (-9500 7150);
DISPLAY INVISIBLE (-9500 7150);
FORCEPROP 2 LAST CDS_LIB passive
J 0
(-9500 7150);
DISPLAY INVISIBLE (-9500 7150);
FORCEPROP 1 LAST CLS_PN G105-0B104-CK
J 0
(-9600 7200);
DISPLAY 1.212766 (-9600 7200);
PAINT GREEN (-9600 7200);
DISPLAY INVISIBLE (-9600 7200);
FORCEPROP 1 LAST $LOCATION C106
J 0
(-9450 7000);
DISPLAY 1.212766 (-9450 7000);
PAINT GREEN (-9450 7000);
FORCEPROP 0 LASTPIN (-9500 7250) $PN 1
R 1
J 0
(-9510 7260);
DISPLAY 0.680851 (-9510 7260);
PAINT MONO (-9510 7260);
FORCEPROP 0 LASTPIN (-9500 7000) $PN 2
R 1
J 2
(-9510 6990);
DISPLAY 0.680851 (-9510 6990);
PAINT MONO (-9510 6990);
FORCEPROP 0 LAST CDS_LOCATION C106
J 0
(-9450 7350);
DISPLAY 1.021277 (-9450 7350);
DISPLAY INVISIBLE (-9450 7350);
FORCEPROP 0 LAST $SEC 1
J 0
(-9450 7350);
DISPLAY 0.680851 (-9450 7350);
PAINT MONO (-9450 7350);
DISPLAY INVISIBLE (-9450 7350);
FORCEPROP 0 LAST CDS_SEC 1
J 0
(-9450 7350);
DISPLAY 1.021277 (-9450 7350);
DISPLAY INVISIBLE (-9450 7350);
FORCEADD CAPACITOR..2
(-9100 7150);
FORCEPROP 1 LAST VALUE 0.1UF
J 0
(-9050 7200);
DISPLAY 1.212766 (-9050 7200);
PAINT GREEN (-9050 7200);
FORCEPROP 0 LAST VOLTAGE 10V
J 0
(-9050 7300);
DISPLAY 1.021277 (-9050 7300);
FORCEPROP 0 LAST PACKAGE 0402
J 0
(-9050 7400);
DISPLAY 1.021277 (-9050 7400);
FORCEPROP 1 LAST PATH I204
J 0
(-9200 7200);
DISPLAY 1.212766 (-9200 7200);
PAINT GREEN (-9200 7200);
DISPLAY INVISIBLE (-9200 7200);
FORCEPROP 1 LAST TOLERANCE 10%
J 0
(-9250 7250);
DISPLAY 1.212766 (-9250 7250);
PAINT GREEN (-9250 7250);
DISPLAY INVISIBLE (-9250 7250);
FORCEPROP 1 LAST CLS_PN G105-0B104-CK
J 0
(-9200 7200);
DISPLAY 1.212766 (-9200 7200);
PAINT GREEN (-9200 7200);
DISPLAY INVISIBLE (-9200 7200);
FORCEPROP 1 LAST CDS_LMAN_SYM_OUTLINE -50,0,50,-50
J 0
(-9100 7150);
DISPLAY 0.468085 (-9100 7150);
PAINT GREEN (-9100 7150);
DISPLAY INVISIBLE (-9100 7150);
FORCEPROP 2 LAST CDS_LIB passive
J 0
(-9100 7150);
DISPLAY INVISIBLE (-9100 7150);
FORCEPROP 1 LAST $LOCATION C113
J 0
(-9050 7000);
DISPLAY 1.212766 (-9050 7000);
PAINT GREEN (-9050 7000);
FORCEPROP 0 LASTPIN (-9100 7250) $PN 1
R 1
J 0
(-9110 7260);
DISPLAY 0.680851 (-9110 7260);
PAINT MONO (-9110 7260);
FORCEPROP 0 LASTPIN (-9100 7000) $PN 2
R 1
J 2
(-9110 6990);
DISPLAY 0.680851 (-9110 6990);
PAINT MONO (-9110 6990);
FORCEPROP 0 LAST CDS_LOCATION C113
J 0
(-9050 7350);
DISPLAY 1.021277 (-9050 7350);
DISPLAY INVISIBLE (-9050 7350);
FORCEPROP 0 LAST $SEC 1
J 0
(-9050 7350);
DISPLAY 0.680851 (-9050 7350);
PAINT MONO (-9050 7350);
DISPLAY INVISIBLE (-9050 7350);
FORCEPROP 0 LAST CDS_SEC 1
J 0
(-9050 7350);
DISPLAY 1.021277 (-9050 7350);
DISPLAY INVISIBLE (-9050 7350);
FORCEADD CAPACITOR..2
(-10950 4300);
FORCEPROP 1 LAST VALUE 0.1UF
J 0
(-10900 4350);
DISPLAY 1.212766 (-10900 4350);
PAINT GREEN (-10900 4350);
FORCEPROP 0 LAST VOLTAGE 10V
J 0
(-10900 4450);
DISPLAY 1.021277 (-10900 4450);
FORCEPROP 0 LAST PACKAGE 0402
J 0
(-10900 4550);
DISPLAY 1.021277 (-10900 4550);
FORCEPROP 1 LAST PATH I205
J 0
(-11050 4350);
DISPLAY 1.212766 (-11050 4350);
PAINT GREEN (-11050 4350);
DISPLAY INVISIBLE (-11050 4350);
FORCEPROP 1 LAST TOLERANCE 10%
J 0
(-11100 4400);
DISPLAY 1.212766 (-11100 4400);
PAINT GREEN (-11100 4400);
DISPLAY INVISIBLE (-11100 4400);
FORCEPROP 1 LAST CDS_LMAN_SYM_OUTLINE -50,0,50,-50
J 0
(-10950 4300);
DISPLAY 0.468085 (-10950 4300);
PAINT GREEN (-10950 4300);
DISPLAY INVISIBLE (-10950 4300);
FORCEPROP 2 LAST CDS_LIB passive
J 0
(-10950 4300);
DISPLAY INVISIBLE (-10950 4300);
FORCEPROP 1 LAST CLS_PN G105-0B104-CK
J 0
(-11050 4350);
DISPLAY 1.212766 (-11050 4350);
PAINT GREEN (-11050 4350);
DISPLAY INVISIBLE (-11050 4350);
FORCEPROP 1 LAST $LOCATION C202
J 0
(-10900 4150);
DISPLAY 1.212766 (-10900 4150);
PAINT GREEN (-10900 4150);
FORCEPROP 0 LASTPIN (-10950 4400) $PN 1
R 1
J 0
(-10960 4410);
DISPLAY 0.680851 (-10960 4410);
PAINT MONO (-10960 4410);
FORCEPROP 0 LASTPIN (-10950 4150) $PN 2
R 1
J 2
(-10960 4140);
DISPLAY 0.680851 (-10960 4140);
PAINT MONO (-10960 4140);
FORCEPROP 0 LAST CDS_LOCATION C202
J 0
(-10900 4500);
DISPLAY 1.021277 (-10900 4500);
DISPLAY INVISIBLE (-10900 4500);
FORCEPROP 0 LAST $SEC 1
J 0
(-10900 4500);
DISPLAY 0.680851 (-10900 4500);
PAINT MONO (-10900 4500);
DISPLAY INVISIBLE (-10900 4500);
FORCEPROP 0 LAST CDS_SEC 1
J 0
(-10900 4500);
DISPLAY 1.021277 (-10900 4500);
DISPLAY INVISIBLE (-10900 4500);
FORCEADD CAPACITOR..2
(-10550 4300);
FORCEPROP 1 LAST VALUE 0.1UF
J 0
(-10500 4350);
DISPLAY 1.212766 (-10500 4350);
PAINT GREEN (-10500 4350);
FORCEPROP 0 LAST VOLTAGE 10V
J 0
(-10500 4450);
DISPLAY 1.021277 (-10500 4450);
FORCEPROP 0 LAST PACKAGE 0402
J 0
(-10500 4550);
DISPLAY 1.021277 (-10500 4550);
FORCEPROP 1 LAST PATH I206
J 0
(-10650 4350);
DISPLAY 1.212766 (-10650 4350);
PAINT GREEN (-10650 4350);
DISPLAY INVISIBLE (-10650 4350);
FORCEPROP 1 LAST TOLERANCE 10%
J 0
(-10700 4400);
DISPLAY 1.212766 (-10700 4400);
PAINT GREEN (-10700 4400);
DISPLAY INVISIBLE (-10700 4400);
FORCEPROP 1 LAST CDS_LMAN_SYM_OUTLINE -50,0,50,-50
J 0
(-10550 4300);
DISPLAY 0.468085 (-10550 4300);
PAINT GREEN (-10550 4300);
DISPLAY INVISIBLE (-10550 4300);
FORCEPROP 2 LAST CDS_LIB passive
J 0
(-10550 4300);
DISPLAY INVISIBLE (-10550 4300);
FORCEPROP 1 LAST CLS_PN G105-0B104-CK
J 0
(-10650 4350);
DISPLAY 1.212766 (-10650 4350);
PAINT GREEN (-10650 4350);
DISPLAY INVISIBLE (-10650 4350);
FORCEPROP 1 LAST $LOCATION C210
J 0
(-10500 4150);
DISPLAY 1.212766 (-10500 4150);
PAINT GREEN (-10500 4150);
FORCEPROP 0 LASTPIN (-10550 4400) $PN 1
R 1
J 0
(-10560 4410);
DISPLAY 0.680851 (-10560 4410);
PAINT MONO (-10560 4410);
FORCEPROP 0 LASTPIN (-10550 4150) $PN 2
R 1
J 2
(-10560 4140);
DISPLAY 0.680851 (-10560 4140);
PAINT MONO (-10560 4140);
FORCEPROP 0 LAST CDS_LOCATION C210
J 0
(-10500 4500);
DISPLAY 1.021277 (-10500 4500);
DISPLAY INVISIBLE (-10500 4500);
FORCEPROP 0 LAST $SEC 1
J 0
(-10500 4500);
DISPLAY 0.680851 (-10500 4500);
PAINT MONO (-10500 4500);
DISPLAY INVISIBLE (-10500 4500);
FORCEPROP 0 LAST CDS_SEC 1
J 0
(-10500 4500);
DISPLAY 1.021277 (-10500 4500);
DISPLAY INVISIBLE (-10500 4500);
FORCEADD CAPACITOR..2
(-10200 4300);
FORCEPROP 0 LAST VOLTAGE 10V
J 0
(-10150 4450);
DISPLAY 1.021277 (-10150 4450);
FORCEPROP 1 LAST VALUE 0.1UF
J 0
(-10150 4350);
DISPLAY 1.212766 (-10150 4350);
PAINT GREEN (-10150 4350);
FORCEPROP 0 LAST PACKAGE 0402
J 0
(-10150 4550);
DISPLAY 1.021277 (-10150 4550);
FORCEPROP 1 LAST PATH I207
J 0
(-10300 4350);
DISPLAY 1.212766 (-10300 4350);
PAINT GREEN (-10300 4350);
DISPLAY INVISIBLE (-10300 4350);
FORCEPROP 1 LAST TOLERANCE 10%
J 0
(-10350 4400);
DISPLAY 1.212766 (-10350 4400);
PAINT GREEN (-10350 4400);
DISPLAY INVISIBLE (-10350 4400);
FORCEPROP 1 LAST CDS_LMAN_SYM_OUTLINE -50,0,50,-50
J 0
(-10200 4300);
DISPLAY 0.468085 (-10200 4300);
PAINT GREEN (-10200 4300);
DISPLAY INVISIBLE (-10200 4300);
FORCEPROP 2 LAST CDS_LIB passive
J 0
(-10200 4300);
DISPLAY INVISIBLE (-10200 4300);
FORCEPROP 1 LAST CLS_PN G105-0B104-CK
J 0
(-10300 4350);
DISPLAY 1.212766 (-10300 4350);
PAINT GREEN (-10300 4350);
DISPLAY INVISIBLE (-10300 4350);
FORCEPROP 1 LAST $LOCATION C215
J 0
(-10150 4150);
DISPLAY 1.212766 (-10150 4150);
PAINT GREEN (-10150 4150);
FORCEPROP 0 LASTPIN (-10200 4400) $PN 1
R 1
J 0
(-10210 4410);
DISPLAY 0.680851 (-10210 4410);
PAINT MONO (-10210 4410);
FORCEPROP 0 LASTPIN (-10200 4150) $PN 2
R 1
J 2
(-10210 4140);
DISPLAY 0.680851 (-10210 4140);
PAINT MONO (-10210 4140);
FORCEPROP 0 LAST CDS_LOCATION C215
J 0
(-10150 4500);
DISPLAY 1.021277 (-10150 4500);
DISPLAY INVISIBLE (-10150 4500);
FORCEPROP 0 LAST $SEC 1
J 0
(-10150 4500);
DISPLAY 0.680851 (-10150 4500);
PAINT MONO (-10150 4500);
DISPLAY INVISIBLE (-10150 4500);
FORCEPROP 0 LAST CDS_SEC 1
J 0
(-10150 4500);
DISPLAY 1.021277 (-10150 4500);
DISPLAY INVISIBLE (-10150 4500);
FORCEADD CAPACITOR..2
(-9800 4300);
FORCEPROP 1 LAST VALUE 0.1UF
J 0
(-9750 4350);
DISPLAY 1.212766 (-9750 4350);
PAINT GREEN (-9750 4350);
FORCEPROP 0 LAST VOLTAGE 10V
J 0
(-9750 4450);
DISPLAY 1.021277 (-9750 4450);
FORCEPROP 0 LAST PACKAGE 0402
J 0
(-9750 4550);
DISPLAY 1.021277 (-9750 4550);
FORCEPROP 1 LAST PATH I208
J 0
(-9900 4350);
DISPLAY 1.212766 (-9900 4350);
PAINT GREEN (-9900 4350);
DISPLAY INVISIBLE (-9900 4350);
FORCEPROP 1 LAST TOLERANCE 10%
J 0
(-9950 4400);
DISPLAY 1.212766 (-9950 4400);
PAINT GREEN (-9950 4400);
DISPLAY INVISIBLE (-9950 4400);
FORCEPROP 2 LAST CDS_LIB passive
J 0
(-9800 4300);
DISPLAY INVISIBLE (-9800 4300);
FORCEPROP 1 LAST CDS_LMAN_SYM_OUTLINE -50,0,50,-50
J 0
(-9800 4300);
DISPLAY 0.468085 (-9800 4300);
PAINT GREEN (-9800 4300);
DISPLAY INVISIBLE (-9800 4300);
FORCEPROP 1 LAST CLS_PN G105-0B104-CK
J 0
(-9900 4350);
DISPLAY 1.212766 (-9900 4350);
PAINT GREEN (-9900 4350);
DISPLAY INVISIBLE (-9900 4350);
FORCEPROP 1 LAST $LOCATION C103
J 0
(-9750 4150);
DISPLAY 1.212766 (-9750 4150);
PAINT GREEN (-9750 4150);
FORCEPROP 0 LASTPIN (-9800 4400) $PN 1
R 1
J 0
(-9810 4410);
DISPLAY 0.680851 (-9810 4410);
PAINT MONO (-9810 4410);
FORCEPROP 0 LASTPIN (-9800 4150) $PN 2
R 1
J 2
(-9810 4140);
DISPLAY 0.680851 (-9810 4140);
PAINT MONO (-9810 4140);
FORCEPROP 0 LAST CDS_LOCATION C103
J 0
(-9750 4500);
DISPLAY 1.021277 (-9750 4500);
DISPLAY INVISIBLE (-9750 4500);
FORCEPROP 0 LAST $SEC 1
J 0
(-9750 4500);
DISPLAY 0.680851 (-9750 4500);
PAINT MONO (-9750 4500);
DISPLAY INVISIBLE (-9750 4500);
FORCEPROP 0 LAST CDS_SEC 1
J 0
(-9750 4500);
DISPLAY 1.021277 (-9750 4500);
DISPLAY INVISIBLE (-9750 4500);
FORCEADD CAPACITOR..2
(-9350 4300);
FORCEPROP 0 LAST VOLTAGE 10V
J 0
(-9300 4450);
DISPLAY 1.021277 (-9300 4450);
FORCEPROP 0 LAST PACKAGE 0402
J 0
(-9300 4550);
DISPLAY 1.021277 (-9300 4550);
FORCEPROP 1 LAST VALUE 0.1UF
J 0
(-9300 4350);
DISPLAY 1.212766 (-9300 4350);
PAINT GREEN (-9300 4350);
FORCEPROP 1 LAST PATH I209
J 0
(-9450 4350);
DISPLAY 1.212766 (-9450 4350);
PAINT GREEN (-9450 4350);
DISPLAY INVISIBLE (-9450 4350);
FORCEPROP 1 LAST TOLERANCE 10%
J 0
(-9500 4400);
DISPLAY 1.212766 (-9500 4400);
PAINT GREEN (-9500 4400);
DISPLAY INVISIBLE (-9500 4400);
FORCEPROP 1 LAST CLS_PN G105-0B104-CK
J 0
(-9450 4350);
DISPLAY 1.212766 (-9450 4350);
PAINT GREEN (-9450 4350);
DISPLAY INVISIBLE (-9450 4350);
FORCEPROP 1 LAST CDS_LMAN_SYM_OUTLINE -50,0,50,-50
J 0
(-9350 4300);
DISPLAY 0.468085 (-9350 4300);
PAINT GREEN (-9350 4300);
DISPLAY INVISIBLE (-9350 4300);
FORCEPROP 2 LAST CDS_LIB passive
J 0
(-9350 4300);
DISPLAY INVISIBLE (-9350 4300);
FORCEPROP 1 LAST $LOCATION C112
J 0
(-9300 4150);
DISPLAY 1.212766 (-9300 4150);
PAINT GREEN (-9300 4150);
FORCEPROP 0 LASTPIN (-9350 4400) $PN 1
R 1
J 0
(-9360 4410);
DISPLAY 0.680851 (-9360 4410);
PAINT MONO (-9360 4410);
FORCEPROP 0 LASTPIN (-9350 4150) $PN 2
R 1
J 2
(-9360 4140);
DISPLAY 0.680851 (-9360 4140);
PAINT MONO (-9360 4140);
FORCEPROP 0 LAST CDS_LOCATION C112
J 0
(-9300 4500);
DISPLAY 1.021277 (-9300 4500);
DISPLAY INVISIBLE (-9300 4500);
FORCEPROP 0 LAST $SEC 1
J 0
(-9300 4500);
DISPLAY 0.680851 (-9300 4500);
PAINT MONO (-9300 4500);
DISPLAY INVISIBLE (-9300 4500);
FORCEPROP 0 LAST CDS_SEC 1
J 0
(-9300 4500);
DISPLAY 1.021277 (-9300 4500);
DISPLAY INVISIBLE (-9300 4500);
FORCEADD CAPACITOR..2
(-8950 4300);
FORCEPROP 1 LAST VALUE 0.1UF
J 0
(-8900 4350);
DISPLAY 1.212766 (-8900 4350);
PAINT GREEN (-8900 4350);
FORCEPROP 0 LAST VOLTAGE 10V
J 0
(-8900 4450);
DISPLAY 1.021277 (-8900 4450);
FORCEPROP 0 LAST PACKAGE 0402
J 0
(-8900 4550);
DISPLAY 1.021277 (-8900 4550);
FORCEPROP 1 LAST PATH I210
J 0
(-9050 4350);
DISPLAY 1.212766 (-9050 4350);
PAINT GREEN (-9050 4350);
DISPLAY INVISIBLE (-9050 4350);
FORCEPROP 1 LAST TOLERANCE 10%
J 0
(-9100 4400);
DISPLAY 1.212766 (-9100 4400);
PAINT GREEN (-9100 4400);
DISPLAY INVISIBLE (-9100 4400);
FORCEPROP 1 LAST CLS_PN G105-0B104-CK
J 0
(-9050 4350);
DISPLAY 1.212766 (-9050 4350);
PAINT GREEN (-9050 4350);
DISPLAY INVISIBLE (-9050 4350);
FORCEPROP 1 LAST CDS_LMAN_SYM_OUTLINE -50,0,50,-50
J 0
(-8950 4300);
DISPLAY 0.468085 (-8950 4300);
PAINT GREEN (-8950 4300);
DISPLAY INVISIBLE (-8950 4300);
FORCEPROP 2 LAST CDS_LIB passive
J 0
(-8950 4300);
DISPLAY INVISIBLE (-8950 4300);
FORCEPROP 1 LAST $LOCATION C119
J 0
(-8900 4150);
DISPLAY 1.212766 (-8900 4150);
PAINT GREEN (-8900 4150);
FORCEPROP 0 LASTPIN (-8950 4400) $PN 1
R 1
J 0
(-8960 4410);
DISPLAY 0.680851 (-8960 4410);
PAINT MONO (-8960 4410);
FORCEPROP 0 LASTPIN (-8950 4150) $PN 2
R 1
J 2
(-8960 4140);
DISPLAY 0.680851 (-8960 4140);
PAINT MONO (-8960 4140);
FORCEPROP 0 LAST CDS_LOCATION C119
J 0
(-8900 4500);
DISPLAY 1.021277 (-8900 4500);
DISPLAY INVISIBLE (-8900 4500);
FORCEPROP 0 LAST $SEC 1
J 0
(-8900 4500);
DISPLAY 0.680851 (-8900 4500);
PAINT MONO (-8900 4500);
DISPLAY INVISIBLE (-8900 4500);
FORCEPROP 0 LAST CDS_SEC 1
J 0
(-8900 4500);
DISPLAY 1.021277 (-8900 4500);
DISPLAY INVISIBLE (-8900 4500);
FORCEADD CAPACITOR..2
(-8600 4300);
FORCEPROP 1 LAST VALUE 0.1UF
J 0
(-8550 4350);
DISPLAY 1.212766 (-8550 4350);
PAINT GREEN (-8550 4350);
FORCEPROP 0 LAST VOLTAGE 10V
J 0
(-8550 4450);
DISPLAY 1.021277 (-8550 4450);
FORCEPROP 0 LAST PACKAGE 0402
J 0
(-8550 4550);
DISPLAY 1.021277 (-8550 4550);
FORCEPROP 1 LAST PATH I211
J 0
(-8700 4350);
DISPLAY 1.212766 (-8700 4350);
PAINT GREEN (-8700 4350);
DISPLAY INVISIBLE (-8700 4350);
FORCEPROP 1 LAST TOLERANCE 10%
J 0
(-8750 4400);
DISPLAY 1.212766 (-8750 4400);
PAINT GREEN (-8750 4400);
DISPLAY INVISIBLE (-8750 4400);
FORCEPROP 1 LAST CLS_PN G105-0B104-CK
J 0
(-8700 4350);
DISPLAY 1.212766 (-8700 4350);
PAINT GREEN (-8700 4350);
DISPLAY INVISIBLE (-8700 4350);
FORCEPROP 1 LAST CDS_LMAN_SYM_OUTLINE -50,0,50,-50
J 0
(-8600 4300);
DISPLAY 0.468085 (-8600 4300);
PAINT GREEN (-8600 4300);
DISPLAY INVISIBLE (-8600 4300);
FORCEPROP 2 LAST CDS_LIB passive
J 0
(-8600 4300);
DISPLAY INVISIBLE (-8600 4300);
FORCEPROP 1 LAST $LOCATION C126
J 0
(-8550 4150);
DISPLAY 1.212766 (-8550 4150);
PAINT GREEN (-8550 4150);
FORCEPROP 0 LASTPIN (-8600 4400) $PN 1
R 1
J 0
(-8610 4410);
DISPLAY 0.680851 (-8610 4410);
PAINT MONO (-8610 4410);
FORCEPROP 0 LASTPIN (-8600 4150) $PN 2
R 1
J 2
(-8610 4140);
DISPLAY 0.680851 (-8610 4140);
PAINT MONO (-8610 4140);
FORCEPROP 0 LAST CDS_LOCATION C126
J 0
(-8550 4500);
DISPLAY 1.021277 (-8550 4500);
DISPLAY INVISIBLE (-8550 4500);
FORCEPROP 0 LAST $SEC 1
J 0
(-8550 4500);
DISPLAY 0.680851 (-8550 4500);
PAINT MONO (-8550 4500);
DISPLAY INVISIBLE (-8550 4500);
FORCEPROP 0 LAST CDS_SEC 1
J 0
(-8550 4500);
DISPLAY 1.021277 (-8550 4500);
DISPLAY INVISIBLE (-8550 4500);
FORCEADD CAPACITOR..2
(-8250 4300);
FORCEPROP 0 LAST VOLTAGE 10V
J 0
(-8200 4450);
DISPLAY 1.021277 (-8200 4450);
FORCEPROP 0 LAST PACKAGE 0402
J 0
(-8200 4550);
DISPLAY 1.021277 (-8200 4550);
FORCEPROP 1 LAST VALUE 0.1UF
J 0
(-8200 4350);
DISPLAY 1.212766 (-8200 4350);
PAINT GREEN (-8200 4350);
FORCEPROP 1 LAST PATH I212
J 0
(-8350 4350);
DISPLAY 1.212766 (-8350 4350);
PAINT GREEN (-8350 4350);
DISPLAY INVISIBLE (-8350 4350);
FORCEPROP 1 LAST TOLERANCE 10%
J 0
(-8400 4400);
DISPLAY 1.212766 (-8400 4400);
PAINT GREEN (-8400 4400);
DISPLAY INVISIBLE (-8400 4400);
FORCEPROP 1 LAST CLS_PN G105-0B104-CK
J 0
(-8350 4350);
DISPLAY 1.212766 (-8350 4350);
PAINT GREEN (-8350 4350);
DISPLAY INVISIBLE (-8350 4350);
FORCEPROP 1 LAST CDS_LMAN_SYM_OUTLINE -50,0,50,-50
J 0
(-8250 4300);
DISPLAY 0.468085 (-8250 4300);
PAINT GREEN (-8250 4300);
DISPLAY INVISIBLE (-8250 4300);
FORCEPROP 2 LAST CDS_LIB passive
J 0
(-8250 4300);
DISPLAY INVISIBLE (-8250 4300);
FORCEPROP 1 LAST $LOCATION C132
J 0
(-8200 4150);
DISPLAY 1.212766 (-8200 4150);
PAINT GREEN (-8200 4150);
FORCEPROP 0 LASTPIN (-8250 4400) $PN 1
R 1
J 0
(-8260 4410);
DISPLAY 0.680851 (-8260 4410);
PAINT MONO (-8260 4410);
FORCEPROP 0 LASTPIN (-8250 4150) $PN 2
R 1
J 2
(-8260 4140);
DISPLAY 0.680851 (-8260 4140);
PAINT MONO (-8260 4140);
FORCEPROP 0 LAST CDS_LOCATION C132
J 0
(-8200 4500);
DISPLAY 1.021277 (-8200 4500);
DISPLAY INVISIBLE (-8200 4500);
FORCEPROP 0 LAST $SEC 1
J 0
(-8200 4500);
DISPLAY 0.680851 (-8200 4500);
PAINT MONO (-8200 4500);
DISPLAY INVISIBLE (-8200 4500);
FORCEPROP 0 LAST CDS_SEC 1
J 0
(-8200 4500);
DISPLAY 1.021277 (-8200 4500);
DISPLAY INVISIBLE (-8200 4500);
FORCEADD CAPACITOR..2
(-7900 4300);
FORCEPROP 0 LAST VOLTAGE 10V
J 0
(-7850 4450);
DISPLAY 1.021277 (-7850 4450);
FORCEPROP 0 LAST PACKAGE 0402
J 0
(-7850 4550);
DISPLAY 1.021277 (-7850 4550);
FORCEPROP 1 LAST VALUE 0.1UF
J 0
(-7850 4350);
DISPLAY 1.212766 (-7850 4350);
PAINT GREEN (-7850 4350);
FORCEPROP 1 LAST PATH I213
J 0
(-8000 4350);
DISPLAY 1.212766 (-8000 4350);
PAINT GREEN (-8000 4350);
DISPLAY INVISIBLE (-8000 4350);
FORCEPROP 1 LAST TOLERANCE 10%
J 0
(-8050 4400);
DISPLAY 1.212766 (-8050 4400);
PAINT GREEN (-8050 4400);
DISPLAY INVISIBLE (-8050 4400);
FORCEPROP 1 LAST CLS_PN G105-0B104-CK
J 0
(-8000 4350);
DISPLAY 1.212766 (-8000 4350);
PAINT GREEN (-8000 4350);
DISPLAY INVISIBLE (-8000 4350);
FORCEPROP 1 LAST CDS_LMAN_SYM_OUTLINE -50,0,50,-50
J 0
(-7900 4300);
DISPLAY 0.468085 (-7900 4300);
PAINT GREEN (-7900 4300);
DISPLAY INVISIBLE (-7900 4300);
FORCEPROP 2 LAST CDS_LIB passive
J 0
(-7900 4300);
DISPLAY INVISIBLE (-7900 4300);
FORCEPROP 1 LAST $LOCATION C139
J 0
(-7850 4150);
DISPLAY 1.212766 (-7850 4150);
PAINT GREEN (-7850 4150);
FORCEPROP 0 LASTPIN (-7900 4400) $PN 1
R 1
J 0
(-7910 4410);
DISPLAY 0.680851 (-7910 4410);
PAINT MONO (-7910 4410);
FORCEPROP 0 LASTPIN (-7900 4150) $PN 2
R 1
J 2
(-7910 4140);
DISPLAY 0.680851 (-7910 4140);
PAINT MONO (-7910 4140);
FORCEPROP 0 LAST CDS_LOCATION C139
J 0
(-7850 4500);
DISPLAY 1.021277 (-7850 4500);
DISPLAY INVISIBLE (-7850 4500);
FORCEPROP 0 LAST $SEC 1
J 0
(-7850 4500);
DISPLAY 0.680851 (-7850 4500);
PAINT MONO (-7850 4500);
DISPLAY INVISIBLE (-7850 4500);
FORCEPROP 0 LAST CDS_SEC 1
J 0
(-7850 4500);
DISPLAY 1.021277 (-7850 4500);
DISPLAY INVISIBLE (-7850 4500);
FORCEADD CAPACITOR..2
(-7500 4300);
FORCEPROP 1 LAST VALUE 0.1UF
J 0
(-7450 4350);
DISPLAY 1.212766 (-7450 4350);
PAINT GREEN (-7450 4350);
FORCEPROP 0 LAST VOLTAGE 10V
J 0
(-7450 4450);
DISPLAY 1.021277 (-7450 4450);
FORCEPROP 0 LAST PACKAGE 0402
J 0
(-7450 4550);
DISPLAY 1.021277 (-7450 4550);
FORCEPROP 1 LAST PATH I214
J 0
(-7600 4350);
DISPLAY 1.212766 (-7600 4350);
PAINT GREEN (-7600 4350);
DISPLAY INVISIBLE (-7600 4350);
FORCEPROP 1 LAST TOLERANCE 10%
J 0
(-7650 4400);
DISPLAY 1.212766 (-7650 4400);
PAINT GREEN (-7650 4400);
DISPLAY INVISIBLE (-7650 4400);
FORCEPROP 1 LAST CLS_PN G105-0B104-CK
J 0
(-7600 4350);
DISPLAY 1.212766 (-7600 4350);
PAINT GREEN (-7600 4350);
DISPLAY INVISIBLE (-7600 4350);
FORCEPROP 1 LAST CDS_LMAN_SYM_OUTLINE -50,0,50,-50
J 0
(-7500 4300);
DISPLAY 0.468085 (-7500 4300);
PAINT GREEN (-7500 4300);
DISPLAY INVISIBLE (-7500 4300);
FORCEPROP 2 LAST CDS_LIB passive
J 0
(-7500 4300);
DISPLAY INVISIBLE (-7500 4300);
FORCEPROP 1 LAST $LOCATION C144
J 0
(-7450 4150);
DISPLAY 1.212766 (-7450 4150);
PAINT GREEN (-7450 4150);
FORCEPROP 0 LASTPIN (-7500 4400) $PN 1
R 1
J 0
(-7510 4410);
DISPLAY 0.680851 (-7510 4410);
PAINT MONO (-7510 4410);
FORCEPROP 0 LASTPIN (-7500 4150) $PN 2
R 1
J 2
(-7510 4140);
DISPLAY 0.680851 (-7510 4140);
PAINT MONO (-7510 4140);
FORCEPROP 0 LAST CDS_LOCATION C144
J 0
(-7450 4500);
DISPLAY 1.021277 (-7450 4500);
DISPLAY INVISIBLE (-7450 4500);
FORCEPROP 0 LAST $SEC 1
J 0
(-7450 4500);
DISPLAY 0.680851 (-7450 4500);
PAINT MONO (-7450 4500);
DISPLAY INVISIBLE (-7450 4500);
FORCEPROP 0 LAST CDS_SEC 1
J 0
(-7450 4500);
DISPLAY 1.021277 (-7450 4500);
DISPLAY INVISIBLE (-7450 4500);
FORCEADD CAPACITOR..2
(-7150 4300);
FORCEPROP 0 LAST VOLTAGE 10V
J 0
(-7100 4450);
DISPLAY 1.021277 (-7100 4450);
FORCEPROP 0 LAST PACKAGE 0402
J 0
(-7100 4550);
DISPLAY 1.021277 (-7100 4550);
FORCEPROP 1 LAST VALUE 0.1UF
J 0
(-7100 4350);
DISPLAY 1.212766 (-7100 4350);
PAINT GREEN (-7100 4350);
FORCEPROP 1 LAST PATH I215
J 0
(-7250 4350);
DISPLAY 1.212766 (-7250 4350);
PAINT GREEN (-7250 4350);
DISPLAY INVISIBLE (-7250 4350);
FORCEPROP 1 LAST TOLERANCE 10%
J 0
(-7300 4400);
DISPLAY 1.212766 (-7300 4400);
PAINT GREEN (-7300 4400);
DISPLAY INVISIBLE (-7300 4400);
FORCEPROP 1 LAST CLS_PN G105-0B104-CK
J 0
(-7250 4350);
DISPLAY 1.212766 (-7250 4350);
PAINT GREEN (-7250 4350);
DISPLAY INVISIBLE (-7250 4350);
FORCEPROP 1 LAST CDS_LMAN_SYM_OUTLINE -50,0,50,-50
J 0
(-7150 4300);
DISPLAY 0.468085 (-7150 4300);
PAINT GREEN (-7150 4300);
DISPLAY INVISIBLE (-7150 4300);
FORCEPROP 2 LAST CDS_LIB passive
J 0
(-7150 4300);
DISPLAY INVISIBLE (-7150 4300);
FORCEPROP 1 LAST $LOCATION C149
J 0
(-7100 4150);
DISPLAY 1.212766 (-7100 4150);
PAINT GREEN (-7100 4150);
FORCEPROP 0 LASTPIN (-7150 4400) $PN 1
R 1
J 0
(-7160 4410);
DISPLAY 0.680851 (-7160 4410);
PAINT MONO (-7160 4410);
FORCEPROP 0 LASTPIN (-7150 4150) $PN 2
R 1
J 2
(-7160 4140);
DISPLAY 0.680851 (-7160 4140);
PAINT MONO (-7160 4140);
FORCEPROP 0 LAST CDS_LOCATION C149
J 0
(-7100 4500);
DISPLAY 1.021277 (-7100 4500);
DISPLAY INVISIBLE (-7100 4500);
FORCEPROP 0 LAST $SEC 1
J 0
(-7100 4500);
DISPLAY 0.680851 (-7100 4500);
PAINT MONO (-7100 4500);
DISPLAY INVISIBLE (-7100 4500);
FORCEPROP 0 LAST CDS_SEC 1
J 0
(-7100 4500);
DISPLAY 1.021277 (-7100 4500);
DISPLAY INVISIBLE (-7100 4500);
FORCEADD CAPACITOR..2
(-10950 3450);
FORCEPROP 1 LAST VALUE 0.1UF
J 0
(-10900 3500);
DISPLAY 1.212766 (-10900 3500);
PAINT GREEN (-10900 3500);
FORCEPROP 0 LAST VOLTAGE 10V
J 0
(-10900 3600);
DISPLAY 1.021277 (-10900 3600);
FORCEPROP 0 LAST PACKAGE 0402
J 0
(-10900 3700);
DISPLAY 1.021277 (-10900 3700);
FORCEPROP 1 LAST PATH I216
J 0
(-11050 3500);
DISPLAY 1.212766 (-11050 3500);
PAINT GREEN (-11050 3500);
DISPLAY INVISIBLE (-11050 3500);
FORCEPROP 1 LAST TOLERANCE 10%
J 0
(-11100 3550);
DISPLAY 1.212766 (-11100 3550);
PAINT GREEN (-11100 3550);
DISPLAY INVISIBLE (-11100 3550);
FORCEPROP 1 LAST CLS_PN G105-0B104-CK
J 0
(-11050 3500);
DISPLAY 1.212766 (-11050 3500);
PAINT GREEN (-11050 3500);
DISPLAY INVISIBLE (-11050 3500);
FORCEPROP 1 LAST CDS_LMAN_SYM_OUTLINE -50,0,50,-50
J 0
(-10950 3450);
DISPLAY 0.468085 (-10950 3450);
PAINT GREEN (-10950 3450);
DISPLAY INVISIBLE (-10950 3450);
FORCEPROP 2 LAST CDS_LIB passive
J 0
(-10950 3450);
DISPLAY INVISIBLE (-10950 3450);
FORCEPROP 1 LAST $LOCATION C203
J 0
(-10900 3300);
DISPLAY 1.212766 (-10900 3300);
PAINT GREEN (-10900 3300);
FORCEPROP 0 LASTPIN (-10950 3550) $PN 1
R 1
J 0
(-10960 3560);
DISPLAY 0.680851 (-10960 3560);
PAINT MONO (-10960 3560);
FORCEPROP 0 LASTPIN (-10950 3300) $PN 2
R 1
J 2
(-10960 3290);
DISPLAY 0.680851 (-10960 3290);
PAINT MONO (-10960 3290);
FORCEPROP 0 LAST CDS_LOCATION C203
J 0
(-10900 3650);
DISPLAY 1.021277 (-10900 3650);
DISPLAY INVISIBLE (-10900 3650);
FORCEPROP 0 LAST $SEC 1
J 0
(-10900 3650);
DISPLAY 0.680851 (-10900 3650);
PAINT MONO (-10900 3650);
DISPLAY INVISIBLE (-10900 3650);
FORCEPROP 0 LAST CDS_SEC 1
J 0
(-10900 3650);
DISPLAY 1.021277 (-10900 3650);
DISPLAY INVISIBLE (-10900 3650);
FORCEADD CAPACITOR..2
(-10550 3450);
FORCEPROP 1 LAST VALUE 0.1UF
J 0
(-10500 3500);
DISPLAY 1.212766 (-10500 3500);
PAINT GREEN (-10500 3500);
FORCEPROP 0 LAST VOLTAGE 10V
J 0
(-10500 3600);
DISPLAY 1.021277 (-10500 3600);
FORCEPROP 0 LAST PACKAGE 0402
J 0
(-10500 3700);
DISPLAY 1.021277 (-10500 3700);
FORCEPROP 1 LAST PATH I217
J 0
(-10650 3500);
DISPLAY 1.212766 (-10650 3500);
PAINT GREEN (-10650 3500);
DISPLAY INVISIBLE (-10650 3500);
FORCEPROP 1 LAST TOLERANCE 10%
J 0
(-10700 3550);
DISPLAY 1.212766 (-10700 3550);
PAINT GREEN (-10700 3550);
DISPLAY INVISIBLE (-10700 3550);
FORCEPROP 1 LAST CLS_PN G105-0B104-CK
J 0
(-10650 3500);
DISPLAY 1.212766 (-10650 3500);
PAINT GREEN (-10650 3500);
DISPLAY INVISIBLE (-10650 3500);
FORCEPROP 1 LAST CDS_LMAN_SYM_OUTLINE -50,0,50,-50
J 0
(-10550 3450);
DISPLAY 0.468085 (-10550 3450);
PAINT GREEN (-10550 3450);
DISPLAY INVISIBLE (-10550 3450);
FORCEPROP 2 LAST CDS_LIB passive
J 0
(-10550 3450);
DISPLAY INVISIBLE (-10550 3450);
FORCEPROP 1 LAST $LOCATION C211
J 0
(-10500 3300);
DISPLAY 1.212766 (-10500 3300);
PAINT GREEN (-10500 3300);
FORCEPROP 0 LASTPIN (-10550 3550) $PN 1
R 1
J 0
(-10560 3560);
DISPLAY 0.680851 (-10560 3560);
PAINT MONO (-10560 3560);
FORCEPROP 0 LASTPIN (-10550 3300) $PN 2
R 1
J 2
(-10560 3290);
DISPLAY 0.680851 (-10560 3290);
PAINT MONO (-10560 3290);
FORCEPROP 0 LAST CDS_LOCATION C211
J 0
(-10500 3650);
DISPLAY 1.021277 (-10500 3650);
DISPLAY INVISIBLE (-10500 3650);
FORCEPROP 0 LAST $SEC 1
J 0
(-10500 3650);
DISPLAY 0.680851 (-10500 3650);
PAINT MONO (-10500 3650);
DISPLAY INVISIBLE (-10500 3650);
FORCEPROP 0 LAST CDS_SEC 1
J 0
(-10500 3650);
DISPLAY 1.021277 (-10500 3650);
DISPLAY INVISIBLE (-10500 3650);
FORCEADD CAPACITOR..2
(-10200 3450);
FORCEPROP 0 LAST VOLTAGE 10V
J 0
(-10150 3600);
DISPLAY 1.021277 (-10150 3600);
FORCEPROP 1 LAST VALUE 0.1UF
J 0
(-10150 3500);
DISPLAY 1.212766 (-10150 3500);
PAINT GREEN (-10150 3500);
FORCEPROP 0 LAST PACKAGE 0402
J 0
(-10150 3700);
DISPLAY 1.021277 (-10150 3700);
FORCEPROP 1 LAST PATH I218
J 0
(-10300 3500);
DISPLAY 1.212766 (-10300 3500);
PAINT GREEN (-10300 3500);
DISPLAY INVISIBLE (-10300 3500);
FORCEPROP 1 LAST TOLERANCE 10%
J 0
(-10350 3550);
DISPLAY 1.212766 (-10350 3550);
PAINT GREEN (-10350 3550);
DISPLAY INVISIBLE (-10350 3550);
FORCEPROP 1 LAST CLS_PN G105-0B104-CK
J 0
(-10300 3500);
DISPLAY 1.212766 (-10300 3500);
PAINT GREEN (-10300 3500);
DISPLAY INVISIBLE (-10300 3500);
FORCEPROP 1 LAST CDS_LMAN_SYM_OUTLINE -50,0,50,-50
J 0
(-10200 3450);
DISPLAY 0.468085 (-10200 3450);
PAINT GREEN (-10200 3450);
DISPLAY INVISIBLE (-10200 3450);
FORCEPROP 2 LAST CDS_LIB passive
J 0
(-10200 3450);
DISPLAY INVISIBLE (-10200 3450);
FORCEPROP 1 LAST $LOCATION C216
J 0
(-10150 3300);
DISPLAY 1.212766 (-10150 3300);
PAINT GREEN (-10150 3300);
FORCEPROP 0 LASTPIN (-10200 3550) $PN 1
R 1
J 0
(-10210 3560);
DISPLAY 0.680851 (-10210 3560);
PAINT MONO (-10210 3560);
FORCEPROP 0 LASTPIN (-10200 3300) $PN 2
R 1
J 2
(-10210 3290);
DISPLAY 0.680851 (-10210 3290);
PAINT MONO (-10210 3290);
FORCEPROP 0 LAST CDS_LOCATION C216
J 0
(-10150 3650);
DISPLAY 1.021277 (-10150 3650);
DISPLAY INVISIBLE (-10150 3650);
FORCEPROP 0 LAST $SEC 1
J 0
(-10150 3650);
DISPLAY 0.680851 (-10150 3650);
PAINT MONO (-10150 3650);
DISPLAY INVISIBLE (-10150 3650);
FORCEPROP 0 LAST CDS_SEC 1
J 0
(-10150 3650);
DISPLAY 1.021277 (-10150 3650);
DISPLAY INVISIBLE (-10150 3650);
FORCEADD CAPACITOR..2
(-9850 3450);
FORCEPROP 0 LAST PACKAGE 0402
J 0
(-9800 3700);
DISPLAY 1.021277 (-9800 3700);
FORCEPROP 0 LAST VOLTAGE 10V
J 0
(-9800 3600);
DISPLAY 1.021277 (-9800 3600);
FORCEPROP 1 LAST VALUE 0.1UF
J 0
(-9800 3500);
DISPLAY 1.212766 (-9800 3500);
PAINT GREEN (-9800 3500);
FORCEPROP 1 LAST PATH I219
J 0
(-9950 3500);
DISPLAY 1.212766 (-9950 3500);
PAINT GREEN (-9950 3500);
DISPLAY INVISIBLE (-9950 3500);
FORCEPROP 1 LAST TOLERANCE 10%
J 0
(-10000 3550);
DISPLAY 1.212766 (-10000 3550);
PAINT GREEN (-10000 3550);
DISPLAY INVISIBLE (-10000 3550);
FORCEPROP 1 LAST CLS_PN G105-0B104-CK
J 0
(-9950 3500);
DISPLAY 1.212766 (-9950 3500);
PAINT GREEN (-9950 3500);
DISPLAY INVISIBLE (-9950 3500);
FORCEPROP 1 LAST CDS_LMAN_SYM_OUTLINE -50,0,50,-50
J 0
(-9850 3450);
DISPLAY 0.468085 (-9850 3450);
PAINT GREEN (-9850 3450);
DISPLAY INVISIBLE (-9850 3450);
FORCEPROP 2 LAST CDS_LIB passive
J 0
(-9850 3450);
DISPLAY INVISIBLE (-9850 3450);
FORCEPROP 1 LAST $LOCATION C221
J 0
(-9800 3300);
DISPLAY 1.212766 (-9800 3300);
PAINT GREEN (-9800 3300);
FORCEPROP 0 LASTPIN (-9850 3550) $PN 1
R 1
J 0
(-9860 3560);
DISPLAY 0.680851 (-9860 3560);
PAINT MONO (-9860 3560);
FORCEPROP 0 LASTPIN (-9850 3300) $PN 2
R 1
J 2
(-9860 3290);
DISPLAY 0.680851 (-9860 3290);
PAINT MONO (-9860 3290);
FORCEPROP 0 LAST CDS_LOCATION C221
J 0
(-9800 3650);
DISPLAY 1.021277 (-9800 3650);
DISPLAY INVISIBLE (-9800 3650);
FORCEPROP 0 LAST $SEC 1
J 0
(-9800 3650);
DISPLAY 0.680851 (-9800 3650);
PAINT MONO (-9800 3650);
DISPLAY INVISIBLE (-9800 3650);
FORCEPROP 0 LAST CDS_SEC 1
J 0
(-9800 3650);
DISPLAY 1.021277 (-9800 3650);
DISPLAY INVISIBLE (-9800 3650);
FORCEADD CAPACITOR..2
(-9500 3450);
FORCEPROP 0 LAST VOLTAGE 10V
J 0
(-9450 3600);
DISPLAY 1.021277 (-9450 3600);
FORCEPROP 0 LAST PACKAGE 0402
J 0
(-9450 3700);
DISPLAY 1.021277 (-9450 3700);
FORCEPROP 1 LAST VALUE 0.1UF
J 0
(-9450 3500);
DISPLAY 1.212766 (-9450 3500);
PAINT GREEN (-9450 3500);
FORCEPROP 1 LAST PATH I220
J 0
(-9600 3500);
DISPLAY 1.212766 (-9600 3500);
PAINT GREEN (-9600 3500);
DISPLAY INVISIBLE (-9600 3500);
FORCEPROP 1 LAST TOLERANCE 10%
J 0
(-9650 3550);
DISPLAY 1.212766 (-9650 3550);
PAINT GREEN (-9650 3550);
DISPLAY INVISIBLE (-9650 3550);
FORCEPROP 1 LAST CLS_PN G105-0B104-CK
J 0
(-9600 3500);
DISPLAY 1.212766 (-9600 3500);
PAINT GREEN (-9600 3500);
DISPLAY INVISIBLE (-9600 3500);
FORCEPROP 1 LAST CDS_LMAN_SYM_OUTLINE -50,0,50,-50
J 0
(-9500 3450);
DISPLAY 0.468085 (-9500 3450);
PAINT GREEN (-9500 3450);
DISPLAY INVISIBLE (-9500 3450);
FORCEPROP 2 LAST CDS_LIB passive
J 0
(-9500 3450);
DISPLAY INVISIBLE (-9500 3450);
FORCEPROP 1 LAST $LOCATION C107
J 0
(-9450 3300);
DISPLAY 1.212766 (-9450 3300);
PAINT GREEN (-9450 3300);
FORCEPROP 0 LASTPIN (-9500 3550) $PN 1
R 1
J 0
(-9510 3560);
DISPLAY 0.680851 (-9510 3560);
PAINT MONO (-9510 3560);
FORCEPROP 0 LASTPIN (-9500 3300) $PN 2
R 1
J 2
(-9510 3290);
DISPLAY 0.680851 (-9510 3290);
PAINT MONO (-9510 3290);
FORCEPROP 0 LAST CDS_LOCATION C107
J 0
(-9450 3650);
DISPLAY 1.021277 (-9450 3650);
DISPLAY INVISIBLE (-9450 3650);
FORCEPROP 0 LAST $SEC 1
J 0
(-9450 3650);
DISPLAY 0.680851 (-9450 3650);
PAINT MONO (-9450 3650);
DISPLAY INVISIBLE (-9450 3650);
FORCEPROP 0 LAST CDS_SEC 1
J 0
(-9450 3650);
DISPLAY 1.021277 (-9450 3650);
DISPLAY INVISIBLE (-9450 3650);
FORCEADD CAPACITOR..2
(-9100 3450);
FORCEPROP 0 LAST VOLTAGE 10V
J 0
(-9050 3600);
DISPLAY 1.021277 (-9050 3600);
FORCEPROP 0 LAST PACKAGE 0402
J 0
(-9050 3700);
DISPLAY 1.021277 (-9050 3700);
FORCEPROP 1 LAST VALUE 0.1UF
J 0
(-9050 3500);
DISPLAY 1.212766 (-9050 3500);
PAINT GREEN (-9050 3500);
FORCEPROP 1 LAST PATH I221
J 0
(-9200 3500);
DISPLAY 1.212766 (-9200 3500);
PAINT GREEN (-9200 3500);
DISPLAY INVISIBLE (-9200 3500);
FORCEPROP 1 LAST TOLERANCE 10%
J 0
(-9250 3550);
DISPLAY 1.212766 (-9250 3550);
PAINT GREEN (-9250 3550);
DISPLAY INVISIBLE (-9250 3550);
FORCEPROP 1 LAST CLS_PN G105-0B104-CK
J 0
(-9200 3500);
DISPLAY 1.212766 (-9200 3500);
PAINT GREEN (-9200 3500);
DISPLAY INVISIBLE (-9200 3500);
FORCEPROP 1 LAST CDS_LMAN_SYM_OUTLINE -50,0,50,-50
J 0
(-9100 3450);
DISPLAY 0.468085 (-9100 3450);
PAINT GREEN (-9100 3450);
DISPLAY INVISIBLE (-9100 3450);
FORCEPROP 2 LAST CDS_LIB passive
J 0
(-9100 3450);
DISPLAY INVISIBLE (-9100 3450);
FORCEPROP 1 LAST $LOCATION C115
J 0
(-9050 3300);
DISPLAY 1.212766 (-9050 3300);
PAINT GREEN (-9050 3300);
FORCEPROP 0 LASTPIN (-9100 3550) $PN 1
R 1
J 0
(-9110 3560);
DISPLAY 0.680851 (-9110 3560);
PAINT MONO (-9110 3560);
FORCEPROP 0 LASTPIN (-9100 3300) $PN 2
R 1
J 2
(-9110 3290);
DISPLAY 0.680851 (-9110 3290);
PAINT MONO (-9110 3290);
FORCEPROP 0 LAST CDS_LOCATION C115
J 0
(-9050 3650);
DISPLAY 1.021277 (-9050 3650);
DISPLAY INVISIBLE (-9050 3650);
FORCEPROP 0 LAST $SEC 1
J 0
(-9050 3650);
DISPLAY 0.680851 (-9050 3650);
PAINT MONO (-9050 3650);
DISPLAY INVISIBLE (-9050 3650);
FORCEPROP 0 LAST CDS_SEC 1
J 0
(-9050 3650);
DISPLAY 1.021277 (-9050 3650);
DISPLAY INVISIBLE (-9050 3650);
FORCEADD CAPACITOR..2
(-8700 3450);
FORCEPROP 0 LAST PACKAGE 0402
J 0
(-8650 3700);
DISPLAY 1.021277 (-8650 3700);
FORCEPROP 0 LAST VOLTAGE 10V
J 0
(-8650 3600);
DISPLAY 1.021277 (-8650 3600);
FORCEPROP 1 LAST VALUE 0.1UF
J 0
(-8650 3500);
DISPLAY 1.212766 (-8650 3500);
PAINT GREEN (-8650 3500);
FORCEPROP 1 LAST PATH I222
J 0
(-8800 3500);
DISPLAY 1.212766 (-8800 3500);
PAINT GREEN (-8800 3500);
DISPLAY INVISIBLE (-8800 3500);
FORCEPROP 1 LAST TOLERANCE 10%
J 0
(-8850 3550);
DISPLAY 1.212766 (-8850 3550);
PAINT GREEN (-8850 3550);
DISPLAY INVISIBLE (-8850 3550);
FORCEPROP 1 LAST CLS_PN G105-0B104-CK
J 0
(-8800 3500);
DISPLAY 1.212766 (-8800 3500);
PAINT GREEN (-8800 3500);
DISPLAY INVISIBLE (-8800 3500);
FORCEPROP 1 LAST CDS_LMAN_SYM_OUTLINE -50,0,50,-50
J 0
(-8700 3450);
DISPLAY 0.468085 (-8700 3450);
PAINT GREEN (-8700 3450);
DISPLAY INVISIBLE (-8700 3450);
FORCEPROP 2 LAST CDS_LIB passive
J 0
(-8700 3450);
DISPLAY INVISIBLE (-8700 3450);
FORCEPROP 1 LAST $LOCATION C223
J 0
(-8650 3300);
DISPLAY 1.212766 (-8650 3300);
PAINT GREEN (-8650 3300);
FORCEPROP 0 LASTPIN (-8700 3550) $PN 1
R 1
J 0
(-8710 3560);
DISPLAY 0.680851 (-8710 3560);
PAINT MONO (-8710 3560);
FORCEPROP 0 LASTPIN (-8700 3300) $PN 2
R 1
J 2
(-8710 3290);
DISPLAY 0.680851 (-8710 3290);
PAINT MONO (-8710 3290);
FORCEPROP 0 LAST CDS_LOCATION C223
J 0
(-8650 3650);
DISPLAY 1.021277 (-8650 3650);
DISPLAY INVISIBLE (-8650 3650);
FORCEPROP 0 LAST $SEC 1
J 0
(-8650 3650);
DISPLAY 0.680851 (-8650 3650);
PAINT MONO (-8650 3650);
DISPLAY INVISIBLE (-8650 3650);
FORCEPROP 0 LAST CDS_SEC 1
J 0
(-8650 3650);
DISPLAY 1.021277 (-8650 3650);
DISPLAY INVISIBLE (-8650 3650);
FORCEADD CAPACITOR..2
(-8350 3450);
FORCEPROP 0 LAST PACKAGE 0402
J 0
(-8300 3700);
DISPLAY 1.021277 (-8300 3700);
FORCEPROP 0 LAST VOLTAGE 10V
J 0
(-8300 3600);
DISPLAY 1.021277 (-8300 3600);
FORCEPROP 1 LAST VALUE 0.1UF
J 0
(-8300 3500);
DISPLAY 1.212766 (-8300 3500);
PAINT GREEN (-8300 3500);
FORCEPROP 1 LAST PATH I223
J 0
(-8450 3500);
DISPLAY 1.212766 (-8450 3500);
PAINT GREEN (-8450 3500);
DISPLAY INVISIBLE (-8450 3500);
FORCEPROP 1 LAST TOLERANCE 10%
J 0
(-8500 3550);
DISPLAY 1.212766 (-8500 3550);
PAINT GREEN (-8500 3550);
DISPLAY INVISIBLE (-8500 3550);
FORCEPROP 1 LAST CLS_PN G105-0B104-CK
J 0
(-8450 3500);
DISPLAY 1.212766 (-8450 3500);
PAINT GREEN (-8450 3500);
DISPLAY INVISIBLE (-8450 3500);
FORCEPROP 1 LAST CDS_LMAN_SYM_OUTLINE -50,0,50,-50
J 0
(-8350 3450);
DISPLAY 0.468085 (-8350 3450);
PAINT GREEN (-8350 3450);
DISPLAY INVISIBLE (-8350 3450);
FORCEPROP 2 LAST CDS_LIB passive
J 0
(-8350 3450);
DISPLAY INVISIBLE (-8350 3450);
FORCEPROP 1 LAST $LOCATION C130
J 0
(-8300 3300);
DISPLAY 1.212766 (-8300 3300);
PAINT GREEN (-8300 3300);
FORCEPROP 0 LASTPIN (-8350 3550) $PN 1
R 1
J 0
(-8360 3560);
DISPLAY 0.680851 (-8360 3560);
PAINT MONO (-8360 3560);
FORCEPROP 0 LASTPIN (-8350 3300) $PN 2
R 1
J 2
(-8360 3290);
DISPLAY 0.680851 (-8360 3290);
PAINT MONO (-8360 3290);
FORCEPROP 0 LAST CDS_LOCATION C130
J 0
(-8300 3650);
DISPLAY 1.021277 (-8300 3650);
DISPLAY INVISIBLE (-8300 3650);
FORCEPROP 0 LAST $SEC 1
J 0
(-8300 3650);
DISPLAY 0.680851 (-8300 3650);
PAINT MONO (-8300 3650);
DISPLAY INVISIBLE (-8300 3650);
FORCEPROP 0 LAST CDS_SEC 1
J 0
(-8300 3650);
DISPLAY 1.021277 (-8300 3650);
DISPLAY INVISIBLE (-8300 3650);
FORCEADD CAPACITOR..2
(-8000 3450);
FORCEPROP 0 LAST PACKAGE 0402
J 0
(-7950 3700);
DISPLAY 1.021277 (-7950 3700);
FORCEPROP 1 LAST VALUE 0.1UF
J 0
(-7950 3500);
DISPLAY 1.212766 (-7950 3500);
PAINT GREEN (-7950 3500);
FORCEPROP 0 LAST VOLTAGE 10V
J 0
(-7950 3600);
DISPLAY 1.021277 (-7950 3600);
FORCEPROP 1 LAST PATH I224
J 0
(-8100 3500);
DISPLAY 1.212766 (-8100 3500);
PAINT GREEN (-8100 3500);
DISPLAY INVISIBLE (-8100 3500);
FORCEPROP 1 LAST TOLERANCE 10%
J 0
(-8150 3550);
DISPLAY 1.212766 (-8150 3550);
PAINT GREEN (-8150 3550);
DISPLAY INVISIBLE (-8150 3550);
FORCEPROP 1 LAST CLS_PN G105-0B104-CK
J 0
(-8100 3500);
DISPLAY 1.212766 (-8100 3500);
PAINT GREEN (-8100 3500);
DISPLAY INVISIBLE (-8100 3500);
FORCEPROP 1 LAST CDS_LMAN_SYM_OUTLINE -50,0,50,-50
J 0
(-8000 3450);
DISPLAY 0.468085 (-8000 3450);
PAINT GREEN (-8000 3450);
DISPLAY INVISIBLE (-8000 3450);
FORCEPROP 2 LAST CDS_LIB passive
J 0
(-8000 3450);
DISPLAY INVISIBLE (-8000 3450);
FORCEPROP 1 LAST $LOCATION C134
J 0
(-7950 3300);
DISPLAY 1.212766 (-7950 3300);
PAINT GREEN (-7950 3300);
FORCEPROP 0 LASTPIN (-8000 3550) $PN 1
R 1
J 0
(-8010 3560);
DISPLAY 0.680851 (-8010 3560);
PAINT MONO (-8010 3560);
FORCEPROP 0 LASTPIN (-8000 3300) $PN 2
R 1
J 2
(-8010 3290);
DISPLAY 0.680851 (-8010 3290);
PAINT MONO (-8010 3290);
FORCEPROP 0 LAST CDS_LOCATION C134
J 0
(-7950 3650);
DISPLAY 1.021277 (-7950 3650);
DISPLAY INVISIBLE (-7950 3650);
FORCEPROP 0 LAST $SEC 1
J 0
(-7950 3650);
DISPLAY 0.680851 (-7950 3650);
PAINT MONO (-7950 3650);
DISPLAY INVISIBLE (-7950 3650);
FORCEPROP 0 LAST CDS_SEC 1
J 0
(-7950 3650);
DISPLAY 1.021277 (-7950 3650);
DISPLAY INVISIBLE (-7950 3650);
FORCEADD CAPACITOR..2
(-7650 3450);
FORCEPROP 1 LAST VALUE 0.1UF
J 0
(-7600 3500);
DISPLAY 1.212766 (-7600 3500);
PAINT GREEN (-7600 3500);
FORCEPROP 0 LAST VOLTAGE 10V
J 0
(-7600 3600);
DISPLAY 1.021277 (-7600 3600);
FORCEPROP 0 LAST PACKAGE 0402
J 0
(-7600 3700);
DISPLAY 1.021277 (-7600 3700);
FORCEPROP 1 LAST PATH I225
J 0
(-7750 3500);
DISPLAY 1.212766 (-7750 3500);
PAINT GREEN (-7750 3500);
DISPLAY INVISIBLE (-7750 3500);
FORCEPROP 1 LAST TOLERANCE 10%
J 0
(-7800 3550);
DISPLAY 1.212766 (-7800 3550);
PAINT GREEN (-7800 3550);
DISPLAY INVISIBLE (-7800 3550);
FORCEPROP 1 LAST CLS_PN G105-0B104-CK
J 0
(-7750 3500);
DISPLAY 1.212766 (-7750 3500);
PAINT GREEN (-7750 3500);
DISPLAY INVISIBLE (-7750 3500);
FORCEPROP 1 LAST CDS_LMAN_SYM_OUTLINE -50,0,50,-50
J 0
(-7650 3450);
DISPLAY 0.468085 (-7650 3450);
PAINT GREEN (-7650 3450);
DISPLAY INVISIBLE (-7650 3450);
FORCEPROP 2 LAST CDS_LIB passive
J 0
(-7650 3450);
DISPLAY INVISIBLE (-7650 3450);
FORCEPROP 1 LAST $LOCATION C140
J 0
(-7600 3300);
DISPLAY 1.212766 (-7600 3300);
PAINT GREEN (-7600 3300);
FORCEPROP 0 LASTPIN (-7650 3550) $PN 1
R 1
J 0
(-7660 3560);
DISPLAY 0.680851 (-7660 3560);
PAINT MONO (-7660 3560);
FORCEPROP 0 LASTPIN (-7650 3300) $PN 2
R 1
J 2
(-7660 3290);
DISPLAY 0.680851 (-7660 3290);
PAINT MONO (-7660 3290);
FORCEPROP 0 LAST CDS_LOCATION C140
J 0
(-7600 3650);
DISPLAY 1.021277 (-7600 3650);
DISPLAY INVISIBLE (-7600 3650);
FORCEPROP 0 LAST $SEC 1
J 0
(-7600 3650);
DISPLAY 0.680851 (-7600 3650);
PAINT MONO (-7600 3650);
DISPLAY INVISIBLE (-7600 3650);
FORCEPROP 0 LAST CDS_SEC 1
J 0
(-7600 3650);
DISPLAY 1.021277 (-7600 3650);
DISPLAY INVISIBLE (-7600 3650);
FORCEADD CAPACITOR..2
(-7250 3450);
FORCEPROP 1 LAST VALUE 0.1UF
J 0
(-7200 3500);
DISPLAY 1.212766 (-7200 3500);
PAINT GREEN (-7200 3500);
FORCEPROP 0 LAST VOLTAGE 10V
J 0
(-7200 3600);
DISPLAY 1.021277 (-7200 3600);
FORCEPROP 0 LAST PACKAGE 0402
J 0
(-7200 3700);
DISPLAY 1.021277 (-7200 3700);
FORCEPROP 1 LAST PATH I226
J 0
(-7350 3500);
DISPLAY 1.212766 (-7350 3500);
PAINT GREEN (-7350 3500);
DISPLAY INVISIBLE (-7350 3500);
FORCEPROP 1 LAST TOLERANCE 10%
J 0
(-7400 3550);
DISPLAY 1.212766 (-7400 3550);
PAINT GREEN (-7400 3550);
DISPLAY INVISIBLE (-7400 3550);
FORCEPROP 1 LAST CLS_PN G105-0B104-CK
J 0
(-7350 3500);
DISPLAY 1.212766 (-7350 3500);
PAINT GREEN (-7350 3500);
DISPLAY INVISIBLE (-7350 3500);
FORCEPROP 1 LAST CDS_LMAN_SYM_OUTLINE -50,0,50,-50
J 0
(-7250 3450);
DISPLAY 0.468085 (-7250 3450);
PAINT GREEN (-7250 3450);
DISPLAY INVISIBLE (-7250 3450);
FORCEPROP 2 LAST CDS_LIB passive
J 0
(-7250 3450);
DISPLAY INVISIBLE (-7250 3450);
FORCEPROP 1 LAST $LOCATION C145
J 0
(-7200 3300);
DISPLAY 1.212766 (-7200 3300);
PAINT GREEN (-7200 3300);
FORCEPROP 0 LASTPIN (-7250 3550) $PN 1
R 1
J 0
(-7260 3560);
DISPLAY 0.680851 (-7260 3560);
PAINT MONO (-7260 3560);
FORCEPROP 0 LASTPIN (-7250 3300) $PN 2
R 1
J 2
(-7260 3290);
DISPLAY 0.680851 (-7260 3290);
PAINT MONO (-7260 3290);
FORCEPROP 0 LAST CDS_LOCATION C145
J 0
(-7200 3650);
DISPLAY 1.021277 (-7200 3650);
DISPLAY INVISIBLE (-7200 3650);
FORCEPROP 0 LAST $SEC 1
J 0
(-7200 3650);
DISPLAY 0.680851 (-7200 3650);
PAINT MONO (-7200 3650);
DISPLAY INVISIBLE (-7200 3650);
FORCEPROP 0 LAST CDS_SEC 1
J 0
(-7200 3650);
DISPLAY 1.021277 (-7200 3650);
DISPLAY INVISIBLE (-7200 3650);
FORCEADD CAPACITOR..2
(-6850 3450);
FORCEPROP 1 LAST VALUE 0.1UF
J 0
(-6800 3500);
DISPLAY 1.212766 (-6800 3500);
PAINT GREEN (-6800 3500);
FORCEPROP 0 LAST VOLTAGE 10V
J 0
(-6800 3600);
DISPLAY 1.021277 (-6800 3600);
FORCEPROP 0 LAST PACKAGE 0402
J 0
(-6800 3700);
DISPLAY 1.021277 (-6800 3700);
FORCEPROP 1 LAST PATH I227
J 0
(-6950 3500);
DISPLAY 1.212766 (-6950 3500);
PAINT GREEN (-6950 3500);
DISPLAY INVISIBLE (-6950 3500);
FORCEPROP 1 LAST TOLERANCE 10%
J 0
(-7000 3550);
DISPLAY 1.212766 (-7000 3550);
PAINT GREEN (-7000 3550);
DISPLAY INVISIBLE (-7000 3550);
FORCEPROP 1 LAST CLS_PN G105-0B104-CK
J 0
(-6950 3500);
DISPLAY 1.212766 (-6950 3500);
PAINT GREEN (-6950 3500);
DISPLAY INVISIBLE (-6950 3500);
FORCEPROP 1 LAST CDS_LMAN_SYM_OUTLINE -50,0,50,-50
J 0
(-6850 3450);
DISPLAY 0.468085 (-6850 3450);
PAINT GREEN (-6850 3450);
DISPLAY INVISIBLE (-6850 3450);
FORCEPROP 2 LAST CDS_LIB passive
J 0
(-6850 3450);
DISPLAY INVISIBLE (-6850 3450);
FORCEPROP 1 LAST $LOCATION C153
J 0
(-6800 3300);
DISPLAY 1.212766 (-6800 3300);
PAINT GREEN (-6800 3300);
FORCEPROP 0 LASTPIN (-6850 3550) $PN 1
R 1
J 0
(-6860 3560);
DISPLAY 0.680851 (-6860 3560);
PAINT MONO (-6860 3560);
FORCEPROP 0 LASTPIN (-6850 3300) $PN 2
R 1
J 2
(-6860 3290);
DISPLAY 0.680851 (-6860 3290);
PAINT MONO (-6860 3290);
FORCEPROP 0 LAST CDS_LOCATION C153
J 0
(-6800 3650);
DISPLAY 1.021277 (-6800 3650);
DISPLAY INVISIBLE (-6800 3650);
FORCEPROP 0 LAST $SEC 1
J 0
(-6800 3650);
DISPLAY 0.680851 (-6800 3650);
PAINT MONO (-6800 3650);
DISPLAY INVISIBLE (-6800 3650);
FORCEPROP 0 LAST CDS_SEC 1
J 0
(-6800 3650);
DISPLAY 1.021277 (-6800 3650);
DISPLAY INVISIBLE (-6800 3650);
FORCEADD CAPACITOR..2
(-6500 3450);
FORCEPROP 1 LAST VALUE 0.1UF
J 0
(-6450 3500);
DISPLAY 1.212766 (-6450 3500);
PAINT GREEN (-6450 3500);
FORCEPROP 0 LAST VOLTAGE 10V
J 0
(-6450 3600);
DISPLAY 1.021277 (-6450 3600);
FORCEPROP 0 LAST PACKAGE 0402
J 0
(-6450 3700);
DISPLAY 1.021277 (-6450 3700);
FORCEPROP 1 LAST PATH I228
J 0
(-6600 3500);
DISPLAY 1.212766 (-6600 3500);
PAINT GREEN (-6600 3500);
DISPLAY INVISIBLE (-6600 3500);
FORCEPROP 1 LAST TOLERANCE 10%
J 0
(-6650 3550);
DISPLAY 1.212766 (-6650 3550);
PAINT GREEN (-6650 3550);
DISPLAY INVISIBLE (-6650 3550);
FORCEPROP 1 LAST CLS_PN G105-0B104-CK
J 0
(-6600 3500);
DISPLAY 1.212766 (-6600 3500);
PAINT GREEN (-6600 3500);
DISPLAY INVISIBLE (-6600 3500);
FORCEPROP 1 LAST CDS_LMAN_SYM_OUTLINE -50,0,50,-50
J 0
(-6500 3450);
DISPLAY 0.468085 (-6500 3450);
PAINT GREEN (-6500 3450);
DISPLAY INVISIBLE (-6500 3450);
FORCEPROP 2 LAST CDS_LIB passive
J 0
(-6500 3450);
DISPLAY INVISIBLE (-6500 3450);
FORCEPROP 1 LAST $LOCATION C157
J 0
(-6450 3300);
DISPLAY 1.212766 (-6450 3300);
PAINT GREEN (-6450 3300);
FORCEPROP 0 LASTPIN (-6500 3550) $PN 1
R 1
J 0
(-6510 3560);
DISPLAY 0.680851 (-6510 3560);
PAINT MONO (-6510 3560);
FORCEPROP 0 LASTPIN (-6500 3300) $PN 2
R 1
J 2
(-6510 3290);
DISPLAY 0.680851 (-6510 3290);
PAINT MONO (-6510 3290);
FORCEPROP 0 LAST CDS_LOCATION C157
J 0
(-6450 3650);
DISPLAY 1.021277 (-6450 3650);
DISPLAY INVISIBLE (-6450 3650);
FORCEPROP 0 LAST $SEC 1
J 0
(-6450 3650);
DISPLAY 0.680851 (-6450 3650);
PAINT MONO (-6450 3650);
DISPLAY INVISIBLE (-6450 3650);
FORCEPROP 0 LAST CDS_SEC 1
J 0
(-6450 3650);
DISPLAY 1.021277 (-6450 3650);
DISPLAY INVISIBLE (-6450 3650);
FORCEADD CAPACITOR..2
(-6150 3450);
FORCEPROP 0 LAST VOLTAGE 10V
J 0
(-6100 3600);
DISPLAY 1.021277 (-6100 3600);
FORCEPROP 1 LAST VALUE 0.1UF
J 0
(-6100 3500);
DISPLAY 1.212766 (-6100 3500);
PAINT GREEN (-6100 3500);
FORCEPROP 0 LAST PACKAGE 0402
J 0
(-6100 3700);
DISPLAY 1.021277 (-6100 3700);
FORCEPROP 1 LAST PATH I229
J 0
(-6250 3500);
DISPLAY 1.212766 (-6250 3500);
PAINT GREEN (-6250 3500);
DISPLAY INVISIBLE (-6250 3500);
FORCEPROP 1 LAST TOLERANCE 10%
J 0
(-6300 3550);
DISPLAY 1.212766 (-6300 3550);
PAINT GREEN (-6300 3550);
DISPLAY INVISIBLE (-6300 3550);
FORCEPROP 1 LAST CLS_PN G105-0B104-CK
J 0
(-6250 3500);
DISPLAY 1.212766 (-6250 3500);
PAINT GREEN (-6250 3500);
DISPLAY INVISIBLE (-6250 3500);
FORCEPROP 1 LAST CDS_LMAN_SYM_OUTLINE -50,0,50,-50
J 0
(-6150 3450);
DISPLAY 0.468085 (-6150 3450);
PAINT GREEN (-6150 3450);
DISPLAY INVISIBLE (-6150 3450);
FORCEPROP 2 LAST CDS_LIB passive
J 0
(-6150 3450);
DISPLAY INVISIBLE (-6150 3450);
FORCEPROP 1 LAST $LOCATION C162
J 0
(-6100 3300);
DISPLAY 1.212766 (-6100 3300);
PAINT GREEN (-6100 3300);
FORCEPROP 0 LASTPIN (-6150 3550) $PN 1
R 1
J 0
(-6160 3560);
DISPLAY 0.680851 (-6160 3560);
PAINT MONO (-6160 3560);
FORCEPROP 0 LASTPIN (-6150 3300) $PN 2
R 1
J 2
(-6160 3290);
DISPLAY 0.680851 (-6160 3290);
PAINT MONO (-6160 3290);
FORCEPROP 0 LAST CDS_LOCATION C162
J 0
(-6100 3650);
DISPLAY 1.021277 (-6100 3650);
DISPLAY INVISIBLE (-6100 3650);
FORCEPROP 0 LAST $SEC 1
J 0
(-6100 3650);
DISPLAY 0.680851 (-6100 3650);
PAINT MONO (-6100 3650);
DISPLAY INVISIBLE (-6100 3650);
FORCEPROP 0 LAST CDS_SEC 1
J 0
(-6100 3650);
DISPLAY 1.021277 (-6100 3650);
DISPLAY INVISIBLE (-6100 3650);
FORCEADD CAPACITOR..2
(-5800 3450);
FORCEPROP 0 LAST VOLTAGE 10V
J 0
(-5750 3600);
DISPLAY 1.021277 (-5750 3600);
FORCEPROP 1 LAST VALUE 0.1UF
J 0
(-5750 3500);
DISPLAY 1.212766 (-5750 3500);
PAINT GREEN (-5750 3500);
FORCEPROP 0 LAST PACKAGE 0402
J 0
(-5750 3700);
DISPLAY 1.021277 (-5750 3700);
FORCEPROP 1 LAST PATH I230
J 0
(-5900 3500);
DISPLAY 1.212766 (-5900 3500);
PAINT GREEN (-5900 3500);
DISPLAY INVISIBLE (-5900 3500);
FORCEPROP 1 LAST TOLERANCE 10%
J 0
(-5950 3550);
DISPLAY 1.212766 (-5950 3550);
PAINT GREEN (-5950 3550);
DISPLAY INVISIBLE (-5950 3550);
FORCEPROP 1 LAST CLS_PN G105-0B104-CK
J 0
(-5900 3500);
DISPLAY 1.212766 (-5900 3500);
PAINT GREEN (-5900 3500);
DISPLAY INVISIBLE (-5900 3500);
FORCEPROP 1 LAST CDS_LMAN_SYM_OUTLINE -50,0,50,-50
J 0
(-5800 3450);
DISPLAY 0.468085 (-5800 3450);
PAINT GREEN (-5800 3450);
DISPLAY INVISIBLE (-5800 3450);
FORCEPROP 2 LAST CDS_LIB passive
J 0
(-5800 3450);
DISPLAY INVISIBLE (-5800 3450);
FORCEPROP 1 LAST $LOCATION C165
J 0
(-5750 3300);
DISPLAY 1.212766 (-5750 3300);
PAINT GREEN (-5750 3300);
FORCEPROP 0 LASTPIN (-5800 3550) $PN 1
R 1
J 0
(-5810 3560);
DISPLAY 0.680851 (-5810 3560);
PAINT MONO (-5810 3560);
FORCEPROP 0 LASTPIN (-5800 3300) $PN 2
R 1
J 2
(-5810 3290);
DISPLAY 0.680851 (-5810 3290);
PAINT MONO (-5810 3290);
FORCEPROP 0 LAST CDS_LOCATION C165
J 0
(-5750 3650);
DISPLAY 1.021277 (-5750 3650);
DISPLAY INVISIBLE (-5750 3650);
FORCEPROP 0 LAST $SEC 1
J 0
(-5750 3650);
DISPLAY 0.680851 (-5750 3650);
PAINT MONO (-5750 3650);
DISPLAY INVISIBLE (-5750 3650);
FORCEPROP 0 LAST CDS_SEC 1
J 0
(-5750 3650);
DISPLAY 1.021277 (-5750 3650);
DISPLAY INVISIBLE (-5750 3650);
FORCEADD CAPACITOR..2
(-10950 2050);
FORCEPROP 0 LAST VOLTAGE 10V
J 0
(-10900 2200);
DISPLAY 1.021277 (-10900 2200);
FORCEPROP 0 LAST PACKAGE 0402
J 0
(-10900 2300);
DISPLAY 1.021277 (-10900 2300);
FORCEPROP 1 LAST VALUE 0.1UF
J 0
(-10900 2100);
DISPLAY 1.212766 (-10900 2100);
PAINT GREEN (-10900 2100);
FORCEPROP 1 LAST PATH I231
J 0
(-11050 2100);
DISPLAY 1.212766 (-11050 2100);
PAINT GREEN (-11050 2100);
DISPLAY INVISIBLE (-11050 2100);
FORCEPROP 1 LAST TOLERANCE 10%
J 0
(-11100 2150);
DISPLAY 1.212766 (-11100 2150);
PAINT GREEN (-11100 2150);
DISPLAY INVISIBLE (-11100 2150);
FORCEPROP 1 LAST CDS_LMAN_SYM_OUTLINE -50,0,50,-50
J 0
(-10950 2050);
DISPLAY 0.468085 (-10950 2050);
PAINT GREEN (-10950 2050);
DISPLAY INVISIBLE (-10950 2050);
FORCEPROP 2 LAST CDS_LIB passive
J 0
(-10950 2050);
DISPLAY INVISIBLE (-10950 2050);
FORCEPROP 1 LAST CLS_PN G105-0B104-CK
J 0
(-11050 2100);
DISPLAY 1.212766 (-11050 2100);
PAINT GREEN (-11050 2100);
DISPLAY INVISIBLE (-11050 2100);
FORCEPROP 1 LAST $LOCATION C204
J 0
(-10900 1900);
DISPLAY 1.212766 (-10900 1900);
PAINT GREEN (-10900 1900);
FORCEPROP 0 LASTPIN (-10950 2150) $PN 1
R 1
J 0
(-10960 2160);
DISPLAY 0.680851 (-10960 2160);
PAINT MONO (-10960 2160);
FORCEPROP 0 LASTPIN (-10950 1900) $PN 2
R 1
J 2
(-10960 1890);
DISPLAY 0.680851 (-10960 1890);
PAINT MONO (-10960 1890);
FORCEPROP 0 LAST CDS_LOCATION C204
J 0
(-10900 2250);
DISPLAY 1.021277 (-10900 2250);
DISPLAY INVISIBLE (-10900 2250);
FORCEPROP 0 LAST $SEC 1
J 0
(-10900 2250);
DISPLAY 0.680851 (-10900 2250);
PAINT MONO (-10900 2250);
DISPLAY INVISIBLE (-10900 2250);
FORCEPROP 0 LAST CDS_SEC 1
J 0
(-10900 2250);
DISPLAY 1.021277 (-10900 2250);
DISPLAY INVISIBLE (-10900 2250);
FORCEADD CAPACITOR..2
(-10600 2050);
FORCEPROP 0 LAST VOLTAGE 10V
J 0
(-10550 2200);
DISPLAY 1.021277 (-10550 2200);
FORCEPROP 0 LAST PACKAGE 0402
J 0
(-10550 2300);
DISPLAY 1.021277 (-10550 2300);
FORCEPROP 1 LAST VALUE 0.1UF
J 0
(-10550 2100);
DISPLAY 1.212766 (-10550 2100);
PAINT GREEN (-10550 2100);
FORCEPROP 1 LAST PATH I232
J 0
(-10700 2100);
DISPLAY 1.212766 (-10700 2100);
PAINT GREEN (-10700 2100);
DISPLAY INVISIBLE (-10700 2100);
FORCEPROP 1 LAST TOLERANCE 10%
J 0
(-10750 2150);
DISPLAY 1.212766 (-10750 2150);
PAINT GREEN (-10750 2150);
DISPLAY INVISIBLE (-10750 2150);
FORCEPROP 1 LAST CLS_PN G105-0B104-CK
J 0
(-10700 2100);
DISPLAY 1.212766 (-10700 2100);
PAINT GREEN (-10700 2100);
DISPLAY INVISIBLE (-10700 2100);
FORCEPROP 1 LAST CDS_LMAN_SYM_OUTLINE -50,0,50,-50
J 0
(-10600 2050);
DISPLAY 0.468085 (-10600 2050);
PAINT GREEN (-10600 2050);
DISPLAY INVISIBLE (-10600 2050);
FORCEPROP 2 LAST CDS_LIB passive
J 0
(-10600 2050);
DISPLAY INVISIBLE (-10600 2050);
FORCEPROP 1 LAST $LOCATION C208
J 0
(-10550 1900);
DISPLAY 1.212766 (-10550 1900);
PAINT GREEN (-10550 1900);
FORCEPROP 0 LASTPIN (-10600 2150) $PN 1
R 1
J 0
(-10610 2160);
DISPLAY 0.680851 (-10610 2160);
PAINT MONO (-10610 2160);
FORCEPROP 0 LASTPIN (-10600 1900) $PN 2
R 1
J 2
(-10610 1890);
DISPLAY 0.680851 (-10610 1890);
PAINT MONO (-10610 1890);
FORCEPROP 0 LAST CDS_LOCATION C208
J 0
(-10550 2250);
DISPLAY 1.021277 (-10550 2250);
DISPLAY INVISIBLE (-10550 2250);
FORCEPROP 0 LAST $SEC 1
J 0
(-10550 2250);
DISPLAY 0.680851 (-10550 2250);
PAINT MONO (-10550 2250);
DISPLAY INVISIBLE (-10550 2250);
FORCEPROP 0 LAST CDS_SEC 1
J 0
(-10550 2250);
DISPLAY 1.021277 (-10550 2250);
DISPLAY INVISIBLE (-10550 2250);
FORCEADD CAPACITOR..2
(-10250 2050);
FORCEPROP 1 LAST VALUE 0.1UF
J 0
(-10200 2100);
DISPLAY 1.212766 (-10200 2100);
PAINT GREEN (-10200 2100);
FORCEPROP 0 LAST PACKAGE 0402
J 0
(-10200 2300);
DISPLAY 1.021277 (-10200 2300);
FORCEPROP 0 LAST VOLTAGE 10V
J 0
(-10200 2200);
DISPLAY 1.021277 (-10200 2200);
FORCEPROP 1 LAST PATH I233
J 0
(-10350 2100);
DISPLAY 1.212766 (-10350 2100);
PAINT GREEN (-10350 2100);
DISPLAY INVISIBLE (-10350 2100);
FORCEPROP 1 LAST TOLERANCE 10%
J 0
(-10400 2150);
DISPLAY 1.212766 (-10400 2150);
PAINT GREEN (-10400 2150);
DISPLAY INVISIBLE (-10400 2150);
FORCEPROP 1 LAST CLS_PN G105-0B104-CK
J 0
(-10350 2100);
DISPLAY 1.212766 (-10350 2100);
PAINT GREEN (-10350 2100);
DISPLAY INVISIBLE (-10350 2100);
FORCEPROP 1 LAST CDS_LMAN_SYM_OUTLINE -50,0,50,-50
J 0
(-10250 2050);
DISPLAY 0.468085 (-10250 2050);
PAINT GREEN (-10250 2050);
DISPLAY INVISIBLE (-10250 2050);
FORCEPROP 2 LAST CDS_LIB passive
J 0
(-10250 2050);
DISPLAY INVISIBLE (-10250 2050);
FORCEPROP 1 LAST $LOCATION C213
J 0
(-10200 1900);
DISPLAY 1.212766 (-10200 1900);
PAINT GREEN (-10200 1900);
FORCEPROP 0 LASTPIN (-10250 2150) $PN 1
R 1
J 0
(-10260 2160);
DISPLAY 0.680851 (-10260 2160);
PAINT MONO (-10260 2160);
FORCEPROP 0 LASTPIN (-10250 1900) $PN 2
R 1
J 2
(-10260 1890);
DISPLAY 0.680851 (-10260 1890);
PAINT MONO (-10260 1890);
FORCEPROP 0 LAST CDS_LOCATION C213
J 0
(-10200 2250);
DISPLAY 1.021277 (-10200 2250);
DISPLAY INVISIBLE (-10200 2250);
FORCEPROP 0 LAST $SEC 1
J 0
(-10200 2250);
DISPLAY 0.680851 (-10200 2250);
PAINT MONO (-10200 2250);
DISPLAY INVISIBLE (-10200 2250);
FORCEPROP 0 LAST CDS_SEC 1
J 0
(-10200 2250);
DISPLAY 1.021277 (-10200 2250);
DISPLAY INVISIBLE (-10200 2250);
FORCEADD CAPACITOR..2
(-9900 2050);
FORCEPROP 0 LAST VOLTAGE 10V
J 0
(-9850 2200);
DISPLAY 1.021277 (-9850 2200);
FORCEPROP 1 LAST VALUE 0.1UF
J 0
(-9850 2100);
DISPLAY 1.212766 (-9850 2100);
PAINT GREEN (-9850 2100);
FORCEPROP 0 LAST PACKAGE 0402
J 0
(-9850 2300);
DISPLAY 1.021277 (-9850 2300);
FORCEPROP 1 LAST PATH I234
J 0
(-10000 2100);
DISPLAY 1.212766 (-10000 2100);
PAINT GREEN (-10000 2100);
DISPLAY INVISIBLE (-10000 2100);
FORCEPROP 1 LAST TOLERANCE 10%
J 0
(-10050 2150);
DISPLAY 1.212766 (-10050 2150);
PAINT GREEN (-10050 2150);
DISPLAY INVISIBLE (-10050 2150);
FORCEPROP 1 LAST CLS_PN G105-0B104-CK
J 0
(-10000 2100);
DISPLAY 1.212766 (-10000 2100);
PAINT GREEN (-10000 2100);
DISPLAY INVISIBLE (-10000 2100);
FORCEPROP 1 LAST CDS_LMAN_SYM_OUTLINE -50,0,50,-50
J 0
(-9900 2050);
DISPLAY 0.468085 (-9900 2050);
PAINT GREEN (-9900 2050);
DISPLAY INVISIBLE (-9900 2050);
FORCEPROP 2 LAST CDS_LIB passive
J 0
(-9900 2050);
DISPLAY INVISIBLE (-9900 2050);
FORCEPROP 1 LAST $LOCATION C220
J 0
(-9850 1900);
DISPLAY 1.212766 (-9850 1900);
PAINT GREEN (-9850 1900);
FORCEPROP 0 LASTPIN (-9900 2150) $PN 1
R 1
J 0
(-9910 2160);
DISPLAY 0.680851 (-9910 2160);
PAINT MONO (-9910 2160);
FORCEPROP 0 LASTPIN (-9900 1900) $PN 2
R 1
J 2
(-9910 1890);
DISPLAY 0.680851 (-9910 1890);
PAINT MONO (-9910 1890);
FORCEPROP 0 LAST CDS_LOCATION C220
J 0
(-9850 2250);
DISPLAY 1.021277 (-9850 2250);
DISPLAY INVISIBLE (-9850 2250);
FORCEPROP 0 LAST $SEC 1
J 0
(-9850 2250);
DISPLAY 0.680851 (-9850 2250);
PAINT MONO (-9850 2250);
DISPLAY INVISIBLE (-9850 2250);
FORCEPROP 0 LAST CDS_SEC 1
J 0
(-9850 2250);
DISPLAY 1.021277 (-9850 2250);
DISPLAY INVISIBLE (-9850 2250);
FORCEADD CAPACITOR..2
(-9500 2050);
FORCEPROP 1 LAST VALUE 0.1UF
J 0
(-9450 2100);
DISPLAY 1.212766 (-9450 2100);
PAINT GREEN (-9450 2100);
FORCEPROP 0 LAST VOLTAGE 10V
J 0
(-9450 2200);
DISPLAY 1.021277 (-9450 2200);
FORCEPROP 0 LAST PACKAGE 0402
J 0
(-9450 2300);
DISPLAY 1.021277 (-9450 2300);
FORCEPROP 1 LAST PATH I235
J 0
(-9600 2100);
DISPLAY 1.212766 (-9600 2100);
PAINT GREEN (-9600 2100);
DISPLAY INVISIBLE (-9600 2100);
FORCEPROP 1 LAST TOLERANCE 10%
J 0
(-9650 2150);
DISPLAY 1.212766 (-9650 2150);
PAINT GREEN (-9650 2150);
DISPLAY INVISIBLE (-9650 2150);
FORCEPROP 1 LAST CLS_PN G105-0B104-CK
J 0
(-9600 2100);
DISPLAY 1.212766 (-9600 2100);
PAINT GREEN (-9600 2100);
DISPLAY INVISIBLE (-9600 2100);
FORCEPROP 1 LAST CDS_LMAN_SYM_OUTLINE -50,0,50,-50
J 0
(-9500 2050);
DISPLAY 0.468085 (-9500 2050);
PAINT GREEN (-9500 2050);
DISPLAY INVISIBLE (-9500 2050);
FORCEPROP 2 LAST CDS_LIB passive
J 0
(-9500 2050);
DISPLAY INVISIBLE (-9500 2050);
FORCEPROP 1 LAST $LOCATION C108
J 0
(-9450 1900);
DISPLAY 1.212766 (-9450 1900);
PAINT GREEN (-9450 1900);
FORCEPROP 0 LASTPIN (-9500 2150) $PN 1
R 1
J 0
(-9510 2160);
DISPLAY 0.680851 (-9510 2160);
PAINT MONO (-9510 2160);
FORCEPROP 0 LASTPIN (-9500 1900) $PN 2
R 1
J 2
(-9510 1890);
DISPLAY 0.680851 (-9510 1890);
PAINT MONO (-9510 1890);
FORCEPROP 0 LAST CDS_LOCATION C108
J 0
(-9450 2250);
DISPLAY 1.021277 (-9450 2250);
DISPLAY INVISIBLE (-9450 2250);
FORCEPROP 0 LAST $SEC 1
J 0
(-9450 2250);
DISPLAY 0.680851 (-9450 2250);
PAINT MONO (-9450 2250);
DISPLAY INVISIBLE (-9450 2250);
FORCEPROP 0 LAST CDS_SEC 1
J 0
(-9450 2250);
DISPLAY 1.021277 (-9450 2250);
DISPLAY INVISIBLE (-9450 2250);
FORCEADD CAPACITOR..2
(-9100 2050);
FORCEPROP 1 LAST VALUE 0.1UF
J 0
(-9050 2100);
DISPLAY 1.212766 (-9050 2100);
PAINT GREEN (-9050 2100);
FORCEPROP 0 LAST VOLTAGE 10V
J 0
(-9050 2200);
DISPLAY 1.021277 (-9050 2200);
FORCEPROP 0 LAST PACKAGE 0402
J 0
(-9050 2300);
DISPLAY 1.021277 (-9050 2300);
FORCEPROP 1 LAST PATH I236
J 0
(-9200 2100);
DISPLAY 1.212766 (-9200 2100);
PAINT GREEN (-9200 2100);
DISPLAY INVISIBLE (-9200 2100);
FORCEPROP 1 LAST TOLERANCE 10%
J 0
(-9250 2150);
DISPLAY 1.212766 (-9250 2150);
PAINT GREEN (-9250 2150);
DISPLAY INVISIBLE (-9250 2150);
FORCEPROP 1 LAST CLS_PN G105-0B104-CK
J 0
(-9200 2100);
DISPLAY 1.212766 (-9200 2100);
PAINT GREEN (-9200 2100);
DISPLAY INVISIBLE (-9200 2100);
FORCEPROP 1 LAST CDS_LMAN_SYM_OUTLINE -50,0,50,-50
J 0
(-9100 2050);
DISPLAY 0.468085 (-9100 2050);
PAINT GREEN (-9100 2050);
DISPLAY INVISIBLE (-9100 2050);
FORCEPROP 2 LAST CDS_LIB passive
J 0
(-9100 2050);
DISPLAY INVISIBLE (-9100 2050);
FORCEPROP 1 LAST $LOCATION C116
J 0
(-9050 1900);
DISPLAY 1.212766 (-9050 1900);
PAINT GREEN (-9050 1900);
FORCEPROP 0 LASTPIN (-9100 2150) $PN 1
R 1
J 0
(-9110 2160);
DISPLAY 0.680851 (-9110 2160);
PAINT MONO (-9110 2160);
FORCEPROP 0 LASTPIN (-9100 1900) $PN 2
R 1
J 2
(-9110 1890);
DISPLAY 0.680851 (-9110 1890);
PAINT MONO (-9110 1890);
FORCEPROP 0 LAST CDS_LOCATION C116
J 0
(-9050 2250);
DISPLAY 1.021277 (-9050 2250);
DISPLAY INVISIBLE (-9050 2250);
FORCEPROP 0 LAST $SEC 1
J 0
(-9050 2250);
DISPLAY 0.680851 (-9050 2250);
PAINT MONO (-9050 2250);
DISPLAY INVISIBLE (-9050 2250);
FORCEPROP 0 LAST CDS_SEC 1
J 0
(-9050 2250);
DISPLAY 1.021277 (-9050 2250);
DISPLAY INVISIBLE (-9050 2250);
FORCEADD CAPACITOR..2
(-8750 2050);
FORCEPROP 0 LAST VOLTAGE 10V
J 0
(-8700 2200);
DISPLAY 1.021277 (-8700 2200);
FORCEPROP 1 LAST VALUE 0.1UF
J 0
(-8700 2100);
DISPLAY 1.212766 (-8700 2100);
PAINT GREEN (-8700 2100);
FORCEPROP 0 LAST PACKAGE 0402
J 0
(-8700 2300);
DISPLAY 1.021277 (-8700 2300);
FORCEPROP 1 LAST PATH I237
J 0
(-8850 2100);
DISPLAY 1.212766 (-8850 2100);
PAINT GREEN (-8850 2100);
DISPLAY INVISIBLE (-8850 2100);
FORCEPROP 1 LAST TOLERANCE 10%
J 0
(-8900 2150);
DISPLAY 1.212766 (-8900 2150);
PAINT GREEN (-8900 2150);
DISPLAY INVISIBLE (-8900 2150);
FORCEPROP 1 LAST CLS_PN G105-0B104-CK
J 0
(-8850 2100);
DISPLAY 1.212766 (-8850 2100);
PAINT GREEN (-8850 2100);
DISPLAY INVISIBLE (-8850 2100);
FORCEPROP 1 LAST CDS_LMAN_SYM_OUTLINE -50,0,50,-50
J 0
(-8750 2050);
DISPLAY 0.468085 (-8750 2050);
PAINT GREEN (-8750 2050);
DISPLAY INVISIBLE (-8750 2050);
FORCEPROP 2 LAST CDS_LIB passive
J 0
(-8750 2050);
DISPLAY INVISIBLE (-8750 2050);
FORCEPROP 1 LAST $LOCATION C122
J 0
(-8700 1900);
DISPLAY 1.212766 (-8700 1900);
PAINT GREEN (-8700 1900);
FORCEPROP 0 LASTPIN (-8750 2150) $PN 1
R 1
J 0
(-8760 2160);
DISPLAY 0.680851 (-8760 2160);
PAINT MONO (-8760 2160);
FORCEPROP 0 LASTPIN (-8750 1900) $PN 2
R 1
J 2
(-8760 1890);
DISPLAY 0.680851 (-8760 1890);
PAINT MONO (-8760 1890);
FORCEPROP 0 LAST CDS_LOCATION C122
J 0
(-8700 2250);
DISPLAY 1.021277 (-8700 2250);
DISPLAY INVISIBLE (-8700 2250);
FORCEPROP 0 LAST $SEC 1
J 0
(-8700 2250);
DISPLAY 0.680851 (-8700 2250);
PAINT MONO (-8700 2250);
DISPLAY INVISIBLE (-8700 2250);
FORCEPROP 0 LAST CDS_SEC 1
J 0
(-8700 2250);
DISPLAY 1.021277 (-8700 2250);
DISPLAY INVISIBLE (-8700 2250);
FORCEADD CAPACITOR..2
(-8400 2050);
FORCEPROP 1 LAST VALUE 0.1UF
J 0
(-8350 2100);
DISPLAY 1.212766 (-8350 2100);
PAINT GREEN (-8350 2100);
FORCEPROP 0 LAST PACKAGE 0402
J 0
(-8350 2300);
DISPLAY 1.021277 (-8350 2300);
FORCEPROP 0 LAST VOLTAGE 10V
J 0
(-8350 2200);
DISPLAY 1.021277 (-8350 2200);
FORCEPROP 1 LAST PATH I238
J 0
(-8500 2100);
DISPLAY 1.212766 (-8500 2100);
PAINT GREEN (-8500 2100);
DISPLAY INVISIBLE (-8500 2100);
FORCEPROP 1 LAST TOLERANCE 10%
J 0
(-8550 2150);
DISPLAY 1.212766 (-8550 2150);
PAINT GREEN (-8550 2150);
DISPLAY INVISIBLE (-8550 2150);
FORCEPROP 1 LAST CLS_PN G105-0B104-CK
J 0
(-8500 2100);
DISPLAY 1.212766 (-8500 2100);
PAINT GREEN (-8500 2100);
DISPLAY INVISIBLE (-8500 2100);
FORCEPROP 1 LAST CDS_LMAN_SYM_OUTLINE -50,0,50,-50
J 0
(-8400 2050);
DISPLAY 0.468085 (-8400 2050);
PAINT GREEN (-8400 2050);
DISPLAY INVISIBLE (-8400 2050);
FORCEPROP 2 LAST CDS_LIB passive
J 0
(-8400 2050);
DISPLAY INVISIBLE (-8400 2050);
FORCEPROP 1 LAST $LOCATION C127
J 0
(-8350 1900);
DISPLAY 1.212766 (-8350 1900);
PAINT GREEN (-8350 1900);
FORCEPROP 0 LASTPIN (-8400 2150) $PN 1
R 1
J 0
(-8410 2160);
DISPLAY 0.680851 (-8410 2160);
PAINT MONO (-8410 2160);
FORCEPROP 0 LASTPIN (-8400 1900) $PN 2
R 1
J 2
(-8410 1890);
DISPLAY 0.680851 (-8410 1890);
PAINT MONO (-8410 1890);
FORCEPROP 0 LAST CDS_LOCATION C127
J 0
(-8350 2250);
DISPLAY 1.021277 (-8350 2250);
DISPLAY INVISIBLE (-8350 2250);
FORCEPROP 0 LAST $SEC 1
J 0
(-8350 2250);
DISPLAY 0.680851 (-8350 2250);
PAINT MONO (-8350 2250);
DISPLAY INVISIBLE (-8350 2250);
FORCEPROP 0 LAST CDS_SEC 1
J 0
(-8350 2250);
DISPLAY 1.021277 (-8350 2250);
DISPLAY INVISIBLE (-8350 2250);
FORCEADD CAPACITOR..2
(-8000 2050);
FORCEPROP 0 LAST VOLTAGE 10V
J 0
(-7950 2200);
DISPLAY 1.021277 (-7950 2200);
FORCEPROP 1 LAST VALUE 0.1UF
J 0
(-7950 2100);
DISPLAY 1.212766 (-7950 2100);
PAINT GREEN (-7950 2100);
FORCEPROP 0 LAST PACKAGE 0402
J 0
(-7950 2300);
DISPLAY 1.021277 (-7950 2300);
FORCEPROP 1 LAST PATH I239
J 0
(-8100 2100);
DISPLAY 1.212766 (-8100 2100);
PAINT GREEN (-8100 2100);
DISPLAY INVISIBLE (-8100 2100);
FORCEPROP 1 LAST TOLERANCE 10%
J 0
(-8150 2150);
DISPLAY 1.212766 (-8150 2150);
PAINT GREEN (-8150 2150);
DISPLAY INVISIBLE (-8150 2150);
FORCEPROP 1 LAST CLS_PN G105-0B104-CK
J 0
(-8100 2100);
DISPLAY 1.212766 (-8100 2100);
PAINT GREEN (-8100 2100);
DISPLAY INVISIBLE (-8100 2100);
FORCEPROP 1 LAST CDS_LMAN_SYM_OUTLINE -50,0,50,-50
J 0
(-8000 2050);
DISPLAY 0.468085 (-8000 2050);
PAINT GREEN (-8000 2050);
DISPLAY INVISIBLE (-8000 2050);
FORCEPROP 2 LAST CDS_LIB passive
J 0
(-8000 2050);
DISPLAY INVISIBLE (-8000 2050);
FORCEPROP 1 LAST $LOCATION C135
J 0
(-7950 1900);
DISPLAY 1.212766 (-7950 1900);
PAINT GREEN (-7950 1900);
FORCEPROP 0 LASTPIN (-8000 2150) $PN 1
R 1
J 0
(-8010 2160);
DISPLAY 0.680851 (-8010 2160);
PAINT MONO (-8010 2160);
FORCEPROP 0 LASTPIN (-8000 1900) $PN 2
R 1
J 2
(-8010 1890);
DISPLAY 0.680851 (-8010 1890);
PAINT MONO (-8010 1890);
FORCEPROP 0 LAST CDS_LOCATION C135
J 0
(-7950 2250);
DISPLAY 1.021277 (-7950 2250);
DISPLAY INVISIBLE (-7950 2250);
FORCEPROP 0 LAST $SEC 1
J 0
(-7950 2250);
DISPLAY 0.680851 (-7950 2250);
PAINT MONO (-7950 2250);
DISPLAY INVISIBLE (-7950 2250);
FORCEPROP 0 LAST CDS_SEC 1
J 0
(-7950 2250);
DISPLAY 1.021277 (-7950 2250);
DISPLAY INVISIBLE (-7950 2250);
FORCEADD CAPACITOR..2
(-7600 2050);
FORCEPROP 0 LAST PACKAGE 0402
J 0
(-7550 2300);
DISPLAY 1.021277 (-7550 2300);
FORCEPROP 1 LAST VALUE 0.1UF
J 0
(-7550 2100);
DISPLAY 1.212766 (-7550 2100);
PAINT GREEN (-7550 2100);
FORCEPROP 0 LAST VOLTAGE 10V
J 0
(-7550 2200);
DISPLAY 1.021277 (-7550 2200);
FORCEPROP 1 LAST PATH I240
J 0
(-7700 2100);
DISPLAY 1.212766 (-7700 2100);
PAINT GREEN (-7700 2100);
DISPLAY INVISIBLE (-7700 2100);
FORCEPROP 1 LAST TOLERANCE 10%
J 0
(-7750 2150);
DISPLAY 1.212766 (-7750 2150);
PAINT GREEN (-7750 2150);
DISPLAY INVISIBLE (-7750 2150);
FORCEPROP 1 LAST CLS_PN G105-0B104-CK
J 0
(-7700 2100);
DISPLAY 1.212766 (-7700 2100);
PAINT GREEN (-7700 2100);
DISPLAY INVISIBLE (-7700 2100);
FORCEPROP 1 LAST CDS_LMAN_SYM_OUTLINE -50,0,50,-50
J 0
(-7600 2050);
DISPLAY 0.468085 (-7600 2050);
PAINT GREEN (-7600 2050);
DISPLAY INVISIBLE (-7600 2050);
FORCEPROP 2 LAST CDS_LIB passive
J 0
(-7600 2050);
DISPLAY INVISIBLE (-7600 2050);
FORCEPROP 1 LAST $LOCATION C142
J 0
(-7550 1900);
DISPLAY 1.212766 (-7550 1900);
PAINT GREEN (-7550 1900);
FORCEPROP 0 LASTPIN (-7600 2150) $PN 1
R 1
J 0
(-7610 2160);
DISPLAY 0.680851 (-7610 2160);
PAINT MONO (-7610 2160);
FORCEPROP 0 LASTPIN (-7600 1900) $PN 2
R 1
J 2
(-7610 1890);
DISPLAY 0.680851 (-7610 1890);
PAINT MONO (-7610 1890);
FORCEPROP 0 LAST CDS_LOCATION C142
J 0
(-7550 2250);
DISPLAY 1.021277 (-7550 2250);
DISPLAY INVISIBLE (-7550 2250);
FORCEPROP 0 LAST $SEC 1
J 0
(-7550 2250);
DISPLAY 0.680851 (-7550 2250);
PAINT MONO (-7550 2250);
DISPLAY INVISIBLE (-7550 2250);
FORCEPROP 0 LAST CDS_SEC 1
J 0
(-7550 2250);
DISPLAY 1.021277 (-7550 2250);
DISPLAY INVISIBLE (-7550 2250);
FORCEADD CAPACITOR..2
(-7250 2050);
FORCEPROP 1 LAST VALUE 0.1UF
J 0
(-7200 2100);
DISPLAY 1.212766 (-7200 2100);
PAINT GREEN (-7200 2100);
FORCEPROP 0 LAST PACKAGE 0402
J 0
(-7200 2300);
DISPLAY 1.021277 (-7200 2300);
FORCEPROP 0 LAST VOLTAGE 10V
J 0
(-7200 2200);
DISPLAY 1.021277 (-7200 2200);
FORCEPROP 1 LAST PATH I241
J 0
(-7350 2100);
DISPLAY 1.212766 (-7350 2100);
PAINT GREEN (-7350 2100);
DISPLAY INVISIBLE (-7350 2100);
FORCEPROP 1 LAST TOLERANCE 10%
J 0
(-7400 2150);
DISPLAY 1.212766 (-7400 2150);
PAINT GREEN (-7400 2150);
DISPLAY INVISIBLE (-7400 2150);
FORCEPROP 1 LAST CDS_LMAN_SYM_OUTLINE -50,0,50,-50
J 0
(-7250 2050);
DISPLAY 0.468085 (-7250 2050);
PAINT GREEN (-7250 2050);
DISPLAY INVISIBLE (-7250 2050);
FORCEPROP 2 LAST CDS_LIB passive
J 0
(-7250 2050);
DISPLAY INVISIBLE (-7250 2050);
FORCEPROP 1 LAST CLS_PN G105-0B104-CK
J 0
(-7350 2100);
DISPLAY 1.212766 (-7350 2100);
PAINT GREEN (-7350 2100);
DISPLAY INVISIBLE (-7350 2100);
FORCEPROP 1 LAST $LOCATION C146
J 0
(-7200 1900);
DISPLAY 1.212766 (-7200 1900);
PAINT GREEN (-7200 1900);
FORCEPROP 0 LASTPIN (-7250 2150) $PN 1
R 1
J 0
(-7260 2160);
DISPLAY 0.680851 (-7260 2160);
PAINT MONO (-7260 2160);
FORCEPROP 0 LASTPIN (-7250 1900) $PN 2
R 1
J 2
(-7260 1890);
DISPLAY 0.680851 (-7260 1890);
PAINT MONO (-7260 1890);
FORCEPROP 0 LAST CDS_LOCATION C146
J 0
(-7200 2250);
DISPLAY 1.021277 (-7200 2250);
DISPLAY INVISIBLE (-7200 2250);
FORCEPROP 0 LAST $SEC 1
J 0
(-7200 2250);
DISPLAY 0.680851 (-7200 2250);
PAINT MONO (-7200 2250);
DISPLAY INVISIBLE (-7200 2250);
FORCEPROP 0 LAST CDS_SEC 1
J 0
(-7200 2250);
DISPLAY 1.021277 (-7200 2250);
DISPLAY INVISIBLE (-7200 2250);
FORCEADD CAPACITOR..2
(-6900 2050);
FORCEPROP 1 LAST VALUE 0.1UF
J 0
(-6850 2100);
DISPLAY 1.212766 (-6850 2100);
PAINT GREEN (-6850 2100);
FORCEPROP 0 LAST PACKAGE 0402
J 0
(-6850 2300);
DISPLAY 1.021277 (-6850 2300);
FORCEPROP 0 LAST VOLTAGE 10V
J 0
(-6850 2200);
DISPLAY 1.021277 (-6850 2200);
FORCEPROP 1 LAST PATH I242
J 0
(-7000 2100);
DISPLAY 1.212766 (-7000 2100);
PAINT GREEN (-7000 2100);
DISPLAY INVISIBLE (-7000 2100);
FORCEPROP 1 LAST CLS_PN G105-0B104-CK
J 0
(-7000 2100);
DISPLAY 1.212766 (-7000 2100);
PAINT GREEN (-7000 2100);
DISPLAY INVISIBLE (-7000 2100);
FORCEPROP 1 LAST CDS_LMAN_SYM_OUTLINE -50,0,50,-50
J 0
(-6900 2050);
DISPLAY 0.468085 (-6900 2050);
PAINT GREEN (-6900 2050);
DISPLAY INVISIBLE (-6900 2050);
FORCEPROP 2 LAST CDS_LIB passive
J 0
(-6900 2050);
DISPLAY INVISIBLE (-6900 2050);
FORCEPROP 1 LAST TOLERANCE 10%
J 0
(-7050 2150);
DISPLAY 1.212766 (-7050 2150);
PAINT GREEN (-7050 2150);
DISPLAY INVISIBLE (-7050 2150);
FORCEPROP 1 LAST $LOCATION C151
J 0
(-6850 1900);
DISPLAY 1.212766 (-6850 1900);
PAINT GREEN (-6850 1900);
FORCEPROP 0 LASTPIN (-6900 2150) $PN 1
R 1
J 0
(-6910 2160);
DISPLAY 0.680851 (-6910 2160);
PAINT MONO (-6910 2160);
FORCEPROP 0 LASTPIN (-6900 1900) $PN 2
R 1
J 2
(-6910 1890);
DISPLAY 0.680851 (-6910 1890);
PAINT MONO (-6910 1890);
FORCEPROP 0 LAST CDS_LOCATION C151
J 0
(-6850 2250);
DISPLAY 1.021277 (-6850 2250);
DISPLAY INVISIBLE (-6850 2250);
FORCEPROP 0 LAST $SEC 1
J 0
(-6850 2250);
DISPLAY 0.680851 (-6850 2250);
PAINT MONO (-6850 2250);
DISPLAY INVISIBLE (-6850 2250);
FORCEPROP 0 LAST CDS_SEC 1
J 0
(-6850 2250);
DISPLAY 1.021277 (-6850 2250);
DISPLAY INVISIBLE (-6850 2250);
FORCEADD CAPACITOR..2
(-8350 7150);
FORCEPROP 1 LAST VALUE 4.7UF
J 0
(-8300 7200);
DISPLAY 1.212766 (-8300 7200);
PAINT GREEN (-8300 7200);
FORCEPROP 0 LAST VOLTAGE 6.3V
J 0
(-8300 7300);
DISPLAY 1.021277 (-8300 7300);
FORCEPROP 0 LAST PACKAGE 0402
J 0
(-8300 7400);
DISPLAY 1.021277 (-8300 7400);
FORCEPROP 1 LAST PATH I243
J 0
(-8450 7200);
DISPLAY 1.212766 (-8450 7200);
PAINT GREEN (-8450 7200);
DISPLAY INVISIBLE (-8450 7200);
FORCEPROP 1 LAST TOLERANCE 20%
J 0
(-8500 7250);
DISPLAY 1.212766 (-8500 7250);
PAINT GREEN (-8500 7250);
DISPLAY INVISIBLE (-8500 7250);
FORCEPROP 1 LAST CLS_PN G105-0F475-BM
J 0
(-8450 7200);
DISPLAY 1.212766 (-8450 7200);
PAINT GREEN (-8450 7200);
DISPLAY INVISIBLE (-8450 7200);
FORCEPROP 2 LAST CDS_LIB passive
J 0
(-8350 7150);
DISPLAY INVISIBLE (-8350 7150);
FORCEPROP 1 LAST CDS_LMAN_SYM_OUTLINE -50,0,50,-50
J 0
(-8350 7150);
DISPLAY 0.468085 (-8350 7150);
PAINT GREEN (-8350 7150);
DISPLAY INVISIBLE (-8350 7150);
FORCEPROP 1 LAST $LOCATION C128
J 0
(-8300 7000);
DISPLAY 1.212766 (-8300 7000);
PAINT GREEN (-8300 7000);
FORCEPROP 0 LASTPIN (-8350 7250) $PN 1
R 1
J 0
(-8360 7260);
DISPLAY 0.680851 (-8360 7260);
PAINT MONO (-8360 7260);
FORCEPROP 0 LASTPIN (-8350 7000) $PN 2
R 1
J 2
(-8360 6990);
DISPLAY 0.680851 (-8360 6990);
PAINT MONO (-8360 6990);
FORCEPROP 0 LAST CDS_LOCATION C128
J 0
(-8300 7350);
DISPLAY 1.021277 (-8300 7350);
DISPLAY INVISIBLE (-8300 7350);
FORCEPROP 0 LAST $SEC 1
J 0
(-8300 7350);
DISPLAY 0.680851 (-8300 7350);
PAINT MONO (-8300 7350);
DISPLAY INVISIBLE (-8300 7350);
FORCEPROP 0 LAST CDS_SEC 1
J 0
(-8300 7350);
DISPLAY 1.021277 (-8300 7350);
DISPLAY INVISIBLE (-8300 7350);
FORCEADD CAPACITOR..2
(-6450 2050);
FORCEPROP 0 LAST PACKAGE 0402
J 0
(-6400 2300);
DISPLAY 1.021277 (-6400 2300);
FORCEPROP 1 LAST VALUE 4.7UF
J 0
(-6400 2100);
DISPLAY 1.212766 (-6400 2100);
PAINT GREEN (-6400 2100);
FORCEPROP 0 LAST VOLTAGE 6.3V
J 0
(-6400 2200);
DISPLAY 1.021277 (-6400 2200);
FORCEPROP 1 LAST PATH I245
J 0
(-6550 2100);
DISPLAY 1.212766 (-6550 2100);
PAINT GREEN (-6550 2100);
DISPLAY INVISIBLE (-6550 2100);
FORCEPROP 1 LAST CLS_PN G105-0F475-BM
J 0
(-6550 2100);
DISPLAY 1.212766 (-6550 2100);
PAINT GREEN (-6550 2100);
DISPLAY INVISIBLE (-6550 2100);
FORCEPROP 2 LAST CDS_LIB passive
J 0
(-6450 2050);
DISPLAY INVISIBLE (-6450 2050);
FORCEPROP 1 LAST CDS_LMAN_SYM_OUTLINE -50,0,50,-50
J 0
(-6450 2050);
DISPLAY 0.468085 (-6450 2050);
PAINT GREEN (-6450 2050);
DISPLAY INVISIBLE (-6450 2050);
FORCEPROP 1 LAST TOLERANCE 20%
J 0
(-6600 2150);
DISPLAY 1.212766 (-6600 2150);
PAINT GREEN (-6600 2150);
DISPLAY INVISIBLE (-6600 2150);
FORCEPROP 1 LAST $LOCATION C160
J 0
(-6400 1900);
DISPLAY 1.212766 (-6400 1900);
PAINT GREEN (-6400 1900);
FORCEPROP 0 LASTPIN (-6450 2150) $PN 1
R 1
J 0
(-6460 2160);
DISPLAY 0.680851 (-6460 2160);
PAINT MONO (-6460 2160);
FORCEPROP 0 LASTPIN (-6450 1900) $PN 2
R 1
J 2
(-6460 1890);
DISPLAY 0.680851 (-6460 1890);
PAINT MONO (-6460 1890);
FORCEPROP 0 LAST CDS_LOCATION C160
J 0
(-6400 2250);
DISPLAY 1.021277 (-6400 2250);
DISPLAY INVISIBLE (-6400 2250);
FORCEPROP 0 LAST $SEC 1
J 0
(-6400 2250);
DISPLAY 0.680851 (-6400 2250);
PAINT MONO (-6400 2250);
DISPLAY INVISIBLE (-6400 2250);
FORCEPROP 0 LAST CDS_SEC 1
J 0
(-6400 2250);
DISPLAY 1.021277 (-6400 2250);
DISPLAY INVISIBLE (-6400 2250);
FORCEADD CAPACITOR..2
(-9100 -650);
FORCEPROP 1 LAST VALUE 4.7UF
J 0
(-9050 -600);
DISPLAY 1.212766 (-9050 -600);
PAINT GREEN (-9050 -600);
FORCEPROP 0 LAST VOLTAGE 6.3V
J 0
(-9050 -500);
DISPLAY 1.021277 (-9050 -500);
FORCEPROP 0 LAST PACKAGE 0402
J 0
(-9050 -400);
DISPLAY 1.021277 (-9050 -400);
FORCEPROP 1 LAST PATH I246
J 0
(-9200 -600);
DISPLAY 1.212766 (-9200 -600);
PAINT GREEN (-9200 -600);
DISPLAY INVISIBLE (-9200 -600);
FORCEPROP 1 LAST TOLERANCE 20%
J 0
(-9250 -550);
DISPLAY 1.212766 (-9250 -550);
PAINT GREEN (-9250 -550);
DISPLAY INVISIBLE (-9250 -550);
FORCEPROP 1 LAST CLS_PN G105-0F475-BM
J 0
(-9200 -600);
DISPLAY 1.212766 (-9200 -600);
PAINT GREEN (-9200 -600);
DISPLAY INVISIBLE (-9200 -600);
FORCEPROP 1 LAST CDS_LMAN_SYM_OUTLINE -50,0,50,-50
J 0
(-9100 -650);
DISPLAY 0.468085 (-9100 -650);
PAINT GREEN (-9100 -650);
DISPLAY INVISIBLE (-9100 -650);
FORCEPROP 2 LAST CDS_LIB passive
J 0
(-9100 -650);
DISPLAY INVISIBLE (-9100 -650);
FORCEPROP 1 LAST $LOCATION C117
J 0
(-9050 -800);
DISPLAY 1.212766 (-9050 -800);
PAINT GREEN (-9050 -800);
FORCEPROP 0 LASTPIN (-9100 -550) $PN 1
R 1
J 0
(-9110 -540);
DISPLAY 0.680851 (-9110 -540);
PAINT MONO (-9110 -540);
FORCEPROP 0 LASTPIN (-9100 -800) $PN 2
R 1
J 2
(-9110 -810);
DISPLAY 0.680851 (-9110 -810);
PAINT MONO (-9110 -810);
FORCEPROP 0 LAST CDS_LOCATION C117
J 0
(-9050 -450);
DISPLAY 1.021277 (-9050 -450);
DISPLAY INVISIBLE (-9050 -450);
FORCEPROP 0 LAST $SEC 1
J 0
(-9050 -450);
DISPLAY 0.680851 (-9050 -450);
PAINT MONO (-9050 -450);
DISPLAY INVISIBLE (-9050 -450);
FORCEPROP 0 LAST CDS_SEC 1
J 0
(-9050 -450);
DISPLAY 1.021277 (-9050 -450);
DISPLAY INVISIBLE (-9050 -450);
FORCEADD CAPACITOR..2
(-8350 450);
FORCEPROP 0 LAST PACKAGE 0402
J 0
(-8300 700);
DISPLAY 1.021277 (-8300 700);
FORCEPROP 0 LAST VOLTAGE 6.3V
J 0
(-8300 600);
DISPLAY 1.021277 (-8300 600);
FORCEPROP 1 LAST VALUE 4.7UF
J 0
(-8300 500);
DISPLAY 1.212766 (-8300 500);
PAINT GREEN (-8300 500);
FORCEPROP 1 LAST PATH I248
J 0
(-8450 500);
DISPLAY 1.212766 (-8450 500);
PAINT GREEN (-8450 500);
DISPLAY INVISIBLE (-8450 500);
FORCEPROP 1 LAST TOLERANCE 20%
J 0
(-8500 550);
DISPLAY 1.212766 (-8500 550);
PAINT GREEN (-8500 550);
DISPLAY INVISIBLE (-8500 550);
FORCEPROP 1 LAST CLS_PN G105-0F475-BM
J 0
(-8450 500);
DISPLAY 1.212766 (-8450 500);
PAINT GREEN (-8450 500);
DISPLAY INVISIBLE (-8450 500);
FORCEPROP 1 LAST CDS_LMAN_SYM_OUTLINE -50,0,50,-50
J 0
(-8350 450);
DISPLAY 0.468085 (-8350 450);
PAINT GREEN (-8350 450);
DISPLAY INVISIBLE (-8350 450);
FORCEPROP 2 LAST CDS_LIB passive
J 0
(-8350 450);
DISPLAY INVISIBLE (-8350 450);
FORCEPROP 1 LAST $LOCATION C131
J 0
(-8300 300);
DISPLAY 1.212766 (-8300 300);
PAINT GREEN (-8300 300);
FORCEPROP 0 LASTPIN (-8350 550) $PN 1
R 1
J 0
(-8360 560);
DISPLAY 0.680851 (-8360 560);
PAINT MONO (-8360 560);
FORCEPROP 0 LASTPIN (-8350 300) $PN 2
R 1
J 2
(-8360 290);
DISPLAY 0.680851 (-8360 290);
PAINT MONO (-8360 290);
FORCEPROP 0 LAST CDS_LOCATION C131
J 0
(-8300 650);
DISPLAY 1.021277 (-8300 650);
DISPLAY INVISIBLE (-8300 650);
FORCEPROP 0 LAST $SEC 1
J 0
(-8300 650);
DISPLAY 0.680851 (-8300 650);
PAINT MONO (-8300 650);
DISPLAY INVISIBLE (-8300 650);
FORCEPROP 0 LAST CDS_SEC 1
J 0
(-8300 650);
DISPLAY 1.021277 (-8300 650);
DISPLAY INVISIBLE (-8300 650);
FORCEADD CAPACITOR..2
(-8000 -650);
FORCEPROP 0 LAST PACKAGE 0402
J 0
(-7950 -400);
DISPLAY 1.021277 (-7950 -400);
FORCEPROP 1 LAST VALUE 0.1UF
J 0
(-7950 -600);
DISPLAY 1.212766 (-7950 -600);
PAINT GREEN (-7950 -600);
FORCEPROP 0 LAST VOLTAGE 10V
J 0
(-7950 -500);
DISPLAY 1.021277 (-7950 -500);
FORCEPROP 1 LAST PATH I249
J 0
(-8100 -600);
DISPLAY 1.212766 (-8100 -600);
PAINT GREEN (-8100 -600);
DISPLAY INVISIBLE (-8100 -600);
FORCEPROP 1 LAST TOLERANCE 10%
J 0
(-8150 -550);
DISPLAY 1.212766 (-8150 -550);
PAINT GREEN (-8150 -550);
DISPLAY INVISIBLE (-8150 -550);
FORCEPROP 1 LAST CLS_PN G105-0B104-CK
J 0
(-8100 -600);
DISPLAY 1.212766 (-8100 -600);
PAINT GREEN (-8100 -600);
DISPLAY INVISIBLE (-8100 -600);
FORCEPROP 1 LAST CDS_LMAN_SYM_OUTLINE -50,0,50,-50
J 0
(-8000 -650);
DISPLAY 0.468085 (-8000 -650);
PAINT GREEN (-8000 -650);
DISPLAY INVISIBLE (-8000 -650);
FORCEPROP 2 LAST CDS_LIB passive
J 0
(-8000 -650);
DISPLAY INVISIBLE (-8000 -650);
FORCEPROP 1 LAST $LOCATION C136
J 0
(-7950 -800);
DISPLAY 1.212766 (-7950 -800);
PAINT GREEN (-7950 -800);
FORCEPROP 0 LASTPIN (-8000 -550) $PN 1
R 1
J 0
(-8010 -540);
DISPLAY 0.680851 (-8010 -540);
PAINT MONO (-8010 -540);
FORCEPROP 0 LASTPIN (-8000 -800) $PN 2
R 1
J 2
(-8010 -810);
DISPLAY 0.680851 (-8010 -810);
PAINT MONO (-8010 -810);
FORCEPROP 0 LAST CDS_LOCATION C136
J 0
(-7950 -450);
DISPLAY 1.021277 (-7950 -450);
DISPLAY INVISIBLE (-7950 -450);
FORCEPROP 0 LAST $SEC 1
J 0
(-7950 -450);
DISPLAY 0.680851 (-7950 -450);
PAINT MONO (-7950 -450);
DISPLAY INVISIBLE (-7950 -450);
FORCEPROP 0 LAST CDS_SEC 1
J 0
(-7950 -450);
DISPLAY 1.021277 (-7950 -450);
DISPLAY INVISIBLE (-7950 -450);
FORCEADD CAPACITOR..2
(-7200 450);
FORCEPROP 1 LAST VALUE 0.1UF
J 0
(-7150 500);
DISPLAY 1.212766 (-7150 500);
PAINT GREEN (-7150 500);
FORCEPROP 0 LAST PACKAGE 0402
J 0
(-7150 700);
DISPLAY 1.021277 (-7150 700);
FORCEPROP 0 LAST VOLTAGE 10V
J 0
(-7150 600);
DISPLAY 1.021277 (-7150 600);
FORCEPROP 1 LAST PATH I250
J 0
(-7300 500);
DISPLAY 1.212766 (-7300 500);
PAINT GREEN (-7300 500);
DISPLAY INVISIBLE (-7300 500);
FORCEPROP 1 LAST TOLERANCE 10%
J 0
(-7350 550);
DISPLAY 1.212766 (-7350 550);
PAINT GREEN (-7350 550);
DISPLAY INVISIBLE (-7350 550);
FORCEPROP 2 LAST CDS_LIB passive
J 0
(-7200 450);
DISPLAY INVISIBLE (-7200 450);
FORCEPROP 1 LAST CDS_LMAN_SYM_OUTLINE -50,0,50,-50
J 0
(-7200 450);
DISPLAY 0.468085 (-7200 450);
PAINT GREEN (-7200 450);
DISPLAY INVISIBLE (-7200 450);
FORCEPROP 1 LAST CLS_PN G105-0B104-CK
J 0
(-7300 500);
DISPLAY 1.212766 (-7300 500);
PAINT GREEN (-7300 500);
DISPLAY INVISIBLE (-7300 500);
FORCEPROP 1 LAST $LOCATION C148
J 0
(-7150 300);
DISPLAY 1.212766 (-7150 300);
PAINT GREEN (-7150 300);
FORCEPROP 0 LASTPIN (-7200 550) $PN 1
R 1
J 0
(-7210 560);
DISPLAY 0.680851 (-7210 560);
PAINT MONO (-7210 560);
FORCEPROP 0 LASTPIN (-7200 300) $PN 2
R 1
J 2
(-7210 290);
DISPLAY 0.680851 (-7210 290);
PAINT MONO (-7210 290);
FORCEPROP 0 LAST CDS_LOCATION C148
J 0
(-7150 650);
DISPLAY 1.021277 (-7150 650);
DISPLAY INVISIBLE (-7150 650);
FORCEPROP 0 LAST $SEC 1
J 0
(-7150 650);
DISPLAY 0.680851 (-7150 650);
PAINT MONO (-7150 650);
DISPLAY INVISIBLE (-7150 650);
FORCEPROP 0 LAST CDS_SEC 1
J 0
(-7150 650);
DISPLAY 1.021277 (-7150 650);
DISPLAY INVISIBLE (-7150 650);
FORCEADD CAPACITOR..2
(-10150 450);
FORCEPROP 0 LAST VOLTAGE 10V
J 0
(-10100 600);
DISPLAY 1.021277 (-10100 600);
FORCEPROP 0 LAST PACKAGE 0402
J 0
(-10100 700);
DISPLAY 1.021277 (-10100 700);
FORCEPROP 1 LAST VALUE 0.1UF
J 0
(-10100 500);
DISPLAY 1.212766 (-10100 500);
PAINT GREEN (-10100 500);
FORCEPROP 1 LAST PATH I251
J 0
(-10250 500);
DISPLAY 1.212766 (-10250 500);
PAINT GREEN (-10250 500);
DISPLAY INVISIBLE (-10250 500);
FORCEPROP 1 LAST CLS_PN G105-0B104-CK
J 0
(-10250 500);
DISPLAY 1.212766 (-10250 500);
PAINT GREEN (-10250 500);
DISPLAY INVISIBLE (-10250 500);
FORCEPROP 2 LAST CDS_LIB passive
J 0
(-10150 450);
DISPLAY INVISIBLE (-10150 450);
FORCEPROP 1 LAST CDS_LMAN_SYM_OUTLINE -50,0,50,-50
J 0
(-10150 450);
DISPLAY 0.468085 (-10150 450);
PAINT GREEN (-10150 450);
DISPLAY INVISIBLE (-10150 450);
FORCEPROP 1 LAST TOLERANCE 10%
J 0
(-10300 550);
DISPLAY 1.212766 (-10300 550);
PAINT GREEN (-10300 550);
DISPLAY INVISIBLE (-10300 550);
FORCEPROP 1 LAST $LOCATION C218
J 0
(-10100 300);
DISPLAY 1.212766 (-10100 300);
PAINT GREEN (-10100 300);
FORCEPROP 0 LASTPIN (-10150 550) $PN 1
R 1
J 0
(-10160 560);
DISPLAY 0.680851 (-10160 560);
PAINT MONO (-10160 560);
FORCEPROP 0 LASTPIN (-10150 300) $PN 2
R 1
J 2
(-10160 290);
DISPLAY 0.680851 (-10160 290);
PAINT MONO (-10160 290);
FORCEPROP 0 LAST CDS_LOCATION C218
J 0
(-10100 650);
DISPLAY 1.021277 (-10100 650);
DISPLAY INVISIBLE (-10100 650);
FORCEPROP 0 LAST $SEC 1
J 0
(-10100 650);
DISPLAY 0.680851 (-10100 650);
PAINT MONO (-10100 650);
DISPLAY INVISIBLE (-10100 650);
FORCEPROP 0 LAST CDS_SEC 1
J 0
(-10100 650);
DISPLAY 1.021277 (-10100 650);
DISPLAY INVISIBLE (-10100 650);
FORCEADD CAPACITOR..2
(-9750 450);
FORCEPROP 0 LAST PACKAGE 0402
J 0
(-9700 700);
DISPLAY 1.021277 (-9700 700);
FORCEPROP 0 LAST VOLTAGE 10V
J 0
(-9700 600);
DISPLAY 1.021277 (-9700 600);
FORCEPROP 1 LAST VALUE 0.1UF
J 0
(-9700 500);
DISPLAY 1.212766 (-9700 500);
PAINT GREEN (-9700 500);
FORCEPROP 1 LAST PATH I252
J 0
(-9850 500);
DISPLAY 1.212766 (-9850 500);
PAINT GREEN (-9850 500);
DISPLAY INVISIBLE (-9850 500);
FORCEPROP 1 LAST TOLERANCE 10%
J 0
(-9900 550);
DISPLAY 1.212766 (-9900 550);
PAINT GREEN (-9900 550);
DISPLAY INVISIBLE (-9900 550);
FORCEPROP 1 LAST CDS_LMAN_SYM_OUTLINE -50,0,50,-50
J 0
(-9750 450);
DISPLAY 0.468085 (-9750 450);
PAINT GREEN (-9750 450);
DISPLAY INVISIBLE (-9750 450);
FORCEPROP 2 LAST CDS_LIB passive
J 0
(-9750 450);
DISPLAY INVISIBLE (-9750 450);
FORCEPROP 1 LAST CLS_PN G105-0B104-CK
J 0
(-9850 500);
DISPLAY 1.212766 (-9850 500);
PAINT GREEN (-9850 500);
DISPLAY INVISIBLE (-9850 500);
FORCEPROP 1 LAST $LOCATION C105
J 0
(-9700 300);
DISPLAY 1.212766 (-9700 300);
PAINT GREEN (-9700 300);
FORCEPROP 0 LASTPIN (-9750 550) $PN 1
R 1
J 0
(-9760 560);
DISPLAY 0.680851 (-9760 560);
PAINT MONO (-9760 560);
FORCEPROP 0 LASTPIN (-9750 300) $PN 2
R 1
J 2
(-9760 290);
DISPLAY 0.680851 (-9760 290);
PAINT MONO (-9760 290);
FORCEPROP 0 LAST CDS_LOCATION C105
J 0
(-9700 650);
DISPLAY 1.021277 (-9700 650);
DISPLAY INVISIBLE (-9700 650);
FORCEPROP 0 LAST $SEC 1
J 0
(-9700 650);
DISPLAY 0.680851 (-9700 650);
PAINT MONO (-9700 650);
DISPLAY INVISIBLE (-9700 650);
FORCEPROP 0 LAST CDS_SEC 1
J 0
(-9700 650);
DISPLAY 1.021277 (-9700 650);
DISPLAY INVISIBLE (-9700 650);
FORCEADD CAPACITOR..2
(-9400 450);
FORCEPROP 0 LAST PACKAGE 0402
J 0
(-9350 700);
DISPLAY 1.021277 (-9350 700);
FORCEPROP 1 LAST VALUE 0.1UF
J 0
(-9350 500);
DISPLAY 1.212766 (-9350 500);
PAINT GREEN (-9350 500);
FORCEPROP 0 LAST VOLTAGE 10V
J 0
(-9350 600);
DISPLAY 1.021277 (-9350 600);
FORCEPROP 1 LAST PATH I253
J 0
(-9500 500);
DISPLAY 1.212766 (-9500 500);
PAINT GREEN (-9500 500);
DISPLAY INVISIBLE (-9500 500);
FORCEPROP 1 LAST TOLERANCE 10%
J 0
(-9550 550);
DISPLAY 1.212766 (-9550 550);
PAINT GREEN (-9550 550);
DISPLAY INVISIBLE (-9550 550);
FORCEPROP 1 LAST CLS_PN G105-0B104-CK
J 0
(-9500 500);
DISPLAY 1.212766 (-9500 500);
PAINT GREEN (-9500 500);
DISPLAY INVISIBLE (-9500 500);
FORCEPROP 1 LAST CDS_LMAN_SYM_OUTLINE -50,0,50,-50
J 0
(-9400 450);
DISPLAY 0.468085 (-9400 450);
PAINT GREEN (-9400 450);
DISPLAY INVISIBLE (-9400 450);
FORCEPROP 2 LAST CDS_LIB passive
J 0
(-9400 450);
DISPLAY INVISIBLE (-9400 450);
FORCEPROP 1 LAST $LOCATION C111
J 0
(-9350 300);
DISPLAY 1.212766 (-9350 300);
PAINT GREEN (-9350 300);
FORCEPROP 0 LASTPIN (-9400 550) $PN 1
R 1
J 0
(-9410 560);
DISPLAY 0.680851 (-9410 560);
PAINT MONO (-9410 560);
FORCEPROP 0 LASTPIN (-9400 300) $PN 2
R 1
J 2
(-9410 290);
DISPLAY 0.680851 (-9410 290);
PAINT MONO (-9410 290);
FORCEPROP 0 LAST CDS_LOCATION C111
J 0
(-9350 650);
DISPLAY 1.021277 (-9350 650);
DISPLAY INVISIBLE (-9350 650);
FORCEPROP 0 LAST $SEC 1
J 0
(-9350 650);
DISPLAY 0.680851 (-9350 650);
PAINT MONO (-9350 650);
DISPLAY INVISIBLE (-9350 650);
FORCEPROP 0 LAST CDS_SEC 1
J 0
(-9350 650);
DISPLAY 1.021277 (-9350 650);
DISPLAY INVISIBLE (-9350 650);
FORCEADD CAPACITOR..2
(-9050 450);
FORCEPROP 1 LAST VALUE 0.1UF
J 0
(-9000 500);
DISPLAY 1.212766 (-9000 500);
PAINT GREEN (-9000 500);
FORCEPROP 0 LAST VOLTAGE 10V
J 0
(-9000 600);
DISPLAY 1.021277 (-9000 600);
FORCEPROP 0 LAST PACKAGE 0402
J 0
(-9000 700);
DISPLAY 1.021277 (-9000 700);
FORCEPROP 1 LAST PATH I254
J 0
(-9150 500);
DISPLAY 1.212766 (-9150 500);
PAINT GREEN (-9150 500);
DISPLAY INVISIBLE (-9150 500);
FORCEPROP 1 LAST TOLERANCE 10%
J 0
(-9200 550);
DISPLAY 1.212766 (-9200 550);
PAINT GREEN (-9200 550);
DISPLAY INVISIBLE (-9200 550);
FORCEPROP 1 LAST CLS_PN G105-0B104-CK
J 0
(-9150 500);
DISPLAY 1.212766 (-9150 500);
PAINT GREEN (-9150 500);
DISPLAY INVISIBLE (-9150 500);
FORCEPROP 1 LAST CDS_LMAN_SYM_OUTLINE -50,0,50,-50
J 0
(-9050 450);
DISPLAY 0.468085 (-9050 450);
PAINT GREEN (-9050 450);
DISPLAY INVISIBLE (-9050 450);
FORCEPROP 2 LAST CDS_LIB passive
J 0
(-9050 450);
DISPLAY INVISIBLE (-9050 450);
FORCEPROP 1 LAST $LOCATION C118
J 0
(-9000 300);
DISPLAY 1.212766 (-9000 300);
PAINT GREEN (-9000 300);
FORCEPROP 0 LASTPIN (-9050 550) $PN 1
R 1
J 0
(-9060 560);
DISPLAY 0.680851 (-9060 560);
PAINT MONO (-9060 560);
FORCEPROP 0 LASTPIN (-9050 300) $PN 2
R 1
J 2
(-9060 290);
DISPLAY 0.680851 (-9060 290);
PAINT MONO (-9060 290);
FORCEPROP 0 LAST CDS_LOCATION C118
J 0
(-9000 650);
DISPLAY 1.021277 (-9000 650);
DISPLAY INVISIBLE (-9000 650);
FORCEPROP 0 LAST $SEC 1
J 0
(-9000 650);
DISPLAY 0.680851 (-9000 650);
PAINT MONO (-9000 650);
DISPLAY INVISIBLE (-9000 650);
FORCEPROP 0 LAST CDS_SEC 1
J 0
(-9000 650);
DISPLAY 1.021277 (-9000 650);
DISPLAY INVISIBLE (-9000 650);
FORCEADD CAPACITOR..2
(-8700 450);
FORCEPROP 1 LAST VALUE 0.1UF
J 0
(-8650 500);
DISPLAY 1.212766 (-8650 500);
PAINT GREEN (-8650 500);
FORCEPROP 0 LAST VOLTAGE 10V
J 0
(-8650 600);
DISPLAY 1.021277 (-8650 600);
FORCEPROP 0 LAST PACKAGE 0402
J 0
(-8650 700);
DISPLAY 1.021277 (-8650 700);
FORCEPROP 1 LAST PATH I255
J 0
(-8800 500);
DISPLAY 1.212766 (-8800 500);
PAINT GREEN (-8800 500);
DISPLAY INVISIBLE (-8800 500);
FORCEPROP 1 LAST TOLERANCE 10%
J 0
(-8850 550);
DISPLAY 1.212766 (-8850 550);
PAINT GREEN (-8850 550);
DISPLAY INVISIBLE (-8850 550);
FORCEPROP 1 LAST CLS_PN G105-0B104-CK
J 0
(-8800 500);
DISPLAY 1.212766 (-8800 500);
PAINT GREEN (-8800 500);
DISPLAY INVISIBLE (-8800 500);
FORCEPROP 1 LAST CDS_LMAN_SYM_OUTLINE -50,0,50,-50
J 0
(-8700 450);
DISPLAY 0.468085 (-8700 450);
PAINT GREEN (-8700 450);
DISPLAY INVISIBLE (-8700 450);
FORCEPROP 2 LAST CDS_LIB passive
J 0
(-8700 450);
DISPLAY INVISIBLE (-8700 450);
FORCEPROP 1 LAST $LOCATION C124
J 0
(-8650 300);
DISPLAY 1.212766 (-8650 300);
PAINT GREEN (-8650 300);
FORCEPROP 0 LASTPIN (-8700 550) $PN 1
R 1
J 0
(-8710 560);
DISPLAY 0.680851 (-8710 560);
PAINT MONO (-8710 560);
FORCEPROP 0 LASTPIN (-8700 300) $PN 2
R 1
J 2
(-8710 290);
DISPLAY 0.680851 (-8710 290);
PAINT MONO (-8710 290);
FORCEPROP 0 LAST CDS_LOCATION C124
J 0
(-8650 650);
DISPLAY 1.021277 (-8650 650);
DISPLAY INVISIBLE (-8650 650);
FORCEPROP 0 LAST $SEC 1
J 0
(-8650 650);
DISPLAY 0.680851 (-8650 650);
PAINT MONO (-8650 650);
DISPLAY INVISIBLE (-8650 650);
FORCEPROP 0 LAST CDS_SEC 1
J 0
(-8650 650);
DISPLAY 1.021277 (-8650 650);
DISPLAY INVISIBLE (-8650 650);
FORCEADD CAPACITOR..2
(-9450 -650);
FORCEPROP 1 LAST VALUE 0.1UF
J 0
(-9400 -600);
DISPLAY 1.212766 (-9400 -600);
PAINT GREEN (-9400 -600);
FORCEPROP 0 LAST VOLTAGE 10V
J 0
(-9400 -500);
DISPLAY 1.021277 (-9400 -500);
FORCEPROP 0 LAST PACKAGE 0402
J 0
(-9400 -400);
DISPLAY 1.021277 (-9400 -400);
FORCEPROP 1 LAST PATH I256
J 0
(-9550 -600);
DISPLAY 1.212766 (-9550 -600);
PAINT GREEN (-9550 -600);
DISPLAY INVISIBLE (-9550 -600);
FORCEPROP 1 LAST TOLERANCE 10%
J 0
(-9600 -550);
DISPLAY 1.212766 (-9600 -550);
PAINT GREEN (-9600 -550);
DISPLAY INVISIBLE (-9600 -550);
FORCEPROP 1 LAST CLS_PN G105-0B104-CK
J 0
(-9550 -600);
DISPLAY 1.212766 (-9550 -600);
PAINT GREEN (-9550 -600);
DISPLAY INVISIBLE (-9550 -600);
FORCEPROP 1 LAST CDS_LMAN_SYM_OUTLINE -50,0,50,-50
J 0
(-9450 -650);
DISPLAY 0.468085 (-9450 -650);
PAINT GREEN (-9450 -650);
DISPLAY INVISIBLE (-9450 -650);
FORCEPROP 2 LAST CDS_LIB passive
J 0
(-9450 -650);
DISPLAY INVISIBLE (-9450 -650);
FORCEPROP 1 LAST $LOCATION C110
J 0
(-9400 -800);
DISPLAY 1.212766 (-9400 -800);
PAINT GREEN (-9400 -800);
FORCEPROP 0 LASTPIN (-9450 -550) $PN 1
R 1
J 0
(-9460 -540);
DISPLAY 0.680851 (-9460 -540);
PAINT MONO (-9460 -540);
FORCEPROP 0 LASTPIN (-9450 -800) $PN 2
R 1
J 2
(-9460 -810);
DISPLAY 0.680851 (-9460 -810);
PAINT MONO (-9460 -810);
FORCEPROP 0 LAST CDS_LOCATION C110
J 0
(-9400 -450);
DISPLAY 1.021277 (-9400 -450);
DISPLAY INVISIBLE (-9400 -450);
FORCEPROP 0 LAST $SEC 1
J 0
(-9400 -450);
DISPLAY 0.680851 (-9400 -450);
PAINT MONO (-9400 -450);
DISPLAY INVISIBLE (-9400 -450);
FORCEPROP 0 LAST CDS_SEC 1
J 0
(-9400 -450);
DISPLAY 1.021277 (-9400 -450);
DISPLAY INVISIBLE (-9400 -450);
FORCEADD CAPACITOR..2
(-9800 -650);
FORCEPROP 0 LAST VOLTAGE 10V
J 0
(-9750 -500);
DISPLAY 1.021277 (-9750 -500);
FORCEPROP 0 LAST PACKAGE 0402
J 0
(-9750 -400);
DISPLAY 1.021277 (-9750 -400);
FORCEPROP 1 LAST VALUE 0.1UF
J 0
(-9750 -600);
DISPLAY 1.212766 (-9750 -600);
PAINT GREEN (-9750 -600);
FORCEPROP 1 LAST PATH I257
J 0
(-9900 -600);
DISPLAY 1.212766 (-9900 -600);
PAINT GREEN (-9900 -600);
DISPLAY INVISIBLE (-9900 -600);
FORCEPROP 1 LAST TOLERANCE 10%
J 0
(-9950 -550);
DISPLAY 1.212766 (-9950 -550);
PAINT GREEN (-9950 -550);
DISPLAY INVISIBLE (-9950 -550);
FORCEPROP 1 LAST CLS_PN G105-0B104-CK
J 0
(-9900 -600);
DISPLAY 1.212766 (-9900 -600);
PAINT GREEN (-9900 -600);
DISPLAY INVISIBLE (-9900 -600);
FORCEPROP 1 LAST CDS_LMAN_SYM_OUTLINE -50,0,50,-50
J 0
(-9800 -650);
DISPLAY 0.468085 (-9800 -650);
PAINT GREEN (-9800 -650);
DISPLAY INVISIBLE (-9800 -650);
FORCEPROP 2 LAST CDS_LIB passive
J 0
(-9800 -650);
DISPLAY INVISIBLE (-9800 -650);
FORCEPROP 1 LAST $LOCATION C104
J 0
(-9750 -800);
DISPLAY 1.212766 (-9750 -800);
PAINT GREEN (-9750 -800);
FORCEPROP 0 LASTPIN (-9800 -550) $PN 1
R 1
J 0
(-9810 -540);
DISPLAY 0.680851 (-9810 -540);
PAINT MONO (-9810 -540);
FORCEPROP 0 LASTPIN (-9800 -800) $PN 2
R 1
J 2
(-9810 -810);
DISPLAY 0.680851 (-9810 -810);
PAINT MONO (-9810 -810);
FORCEPROP 0 LAST CDS_LOCATION C104
J 0
(-9750 -450);
DISPLAY 1.021277 (-9750 -450);
DISPLAY INVISIBLE (-9750 -450);
FORCEPROP 0 LAST $SEC 1
J 0
(-9750 -450);
DISPLAY 0.680851 (-9750 -450);
PAINT MONO (-9750 -450);
DISPLAY INVISIBLE (-9750 -450);
FORCEPROP 0 LAST CDS_SEC 1
J 0
(-9750 -450);
DISPLAY 1.021277 (-9750 -450);
DISPLAY INVISIBLE (-9750 -450);
FORCEADD CAPACITOR..2
(-10200 -650);
FORCEPROP 0 LAST VOLTAGE 10V
J 0
(-10150 -500);
DISPLAY 1.021277 (-10150 -500);
FORCEPROP 0 LAST PACKAGE 0402
J 0
(-10150 -400);
DISPLAY 1.021277 (-10150 -400);
FORCEPROP 1 LAST VALUE 0.1UF
J 0
(-10150 -600);
DISPLAY 1.212766 (-10150 -600);
PAINT GREEN (-10150 -600);
FORCEPROP 1 LAST PATH I258
J 0
(-10300 -600);
DISPLAY 1.212766 (-10300 -600);
PAINT GREEN (-10300 -600);
DISPLAY INVISIBLE (-10300 -600);
FORCEPROP 1 LAST TOLERANCE 10%
J 0
(-10350 -550);
DISPLAY 1.212766 (-10350 -550);
PAINT GREEN (-10350 -550);
DISPLAY INVISIBLE (-10350 -550);
FORCEPROP 1 LAST CLS_PN G105-0B104-CK
J 0
(-10300 -600);
DISPLAY 1.212766 (-10300 -600);
PAINT GREEN (-10300 -600);
DISPLAY INVISIBLE (-10300 -600);
FORCEPROP 1 LAST CDS_LMAN_SYM_OUTLINE -50,0,50,-50
J 0
(-10200 -650);
DISPLAY 0.468085 (-10200 -650);
PAINT GREEN (-10200 -650);
DISPLAY INVISIBLE (-10200 -650);
FORCEPROP 2 LAST CDS_LIB passive
J 0
(-10200 -650);
DISPLAY INVISIBLE (-10200 -650);
FORCEPROP 1 LAST $LOCATION C217
J 0
(-10150 -800);
DISPLAY 1.212766 (-10150 -800);
PAINT GREEN (-10150 -800);
FORCEPROP 0 LASTPIN (-10200 -550) $PN 1
R 1
J 0
(-10210 -540);
DISPLAY 0.680851 (-10210 -540);
PAINT MONO (-10210 -540);
FORCEPROP 0 LASTPIN (-10200 -800) $PN 2
R 1
J 2
(-10210 -810);
DISPLAY 0.680851 (-10210 -810);
PAINT MONO (-10210 -810);
FORCEPROP 0 LAST CDS_LOCATION C217
J 0
(-10150 -450);
DISPLAY 1.021277 (-10150 -450);
DISPLAY INVISIBLE (-10150 -450);
FORCEPROP 0 LAST $SEC 1
J 0
(-10150 -450);
DISPLAY 0.680851 (-10150 -450);
PAINT MONO (-10150 -450);
DISPLAY INVISIBLE (-10150 -450);
FORCEPROP 0 LAST CDS_SEC 1
J 0
(-10150 -450);
DISPLAY 1.021277 (-10150 -450);
DISPLAY INVISIBLE (-10150 -450);
FORCEADD CAPACITOR..2
(-10600 -650);
FORCEPROP 1 LAST VALUE 0.1UF
J 0
(-10550 -600);
DISPLAY 1.212766 (-10550 -600);
PAINT GREEN (-10550 -600);
FORCEPROP 0 LAST VOLTAGE 10V
J 0
(-10550 -500);
DISPLAY 1.021277 (-10550 -500);
FORCEPROP 0 LAST PACKAGE 0402
J 0
(-10550 -400);
DISPLAY 1.021277 (-10550 -400);
FORCEPROP 1 LAST PATH I259
J 0
(-10700 -600);
DISPLAY 1.212766 (-10700 -600);
PAINT GREEN (-10700 -600);
DISPLAY INVISIBLE (-10700 -600);
FORCEPROP 1 LAST TOLERANCE 10%
J 0
(-10750 -550);
DISPLAY 1.212766 (-10750 -550);
PAINT GREEN (-10750 -550);
DISPLAY INVISIBLE (-10750 -550);
FORCEPROP 1 LAST CLS_PN G105-0B104-CK
J 0
(-10700 -600);
DISPLAY 1.212766 (-10700 -600);
PAINT GREEN (-10700 -600);
DISPLAY INVISIBLE (-10700 -600);
FORCEPROP 1 LAST CDS_LMAN_SYM_OUTLINE -50,0,50,-50
J 0
(-10600 -650);
DISPLAY 0.468085 (-10600 -650);
PAINT GREEN (-10600 -650);
DISPLAY INVISIBLE (-10600 -650);
FORCEPROP 2 LAST CDS_LIB passive
J 0
(-10600 -650);
DISPLAY INVISIBLE (-10600 -650);
FORCEPROP 1 LAST $LOCATION C209
J 0
(-10550 -800);
DISPLAY 1.212766 (-10550 -800);
PAINT GREEN (-10550 -800);
FORCEPROP 0 LASTPIN (-10600 -550) $PN 1
R 1
J 0
(-10610 -540);
DISPLAY 0.680851 (-10610 -540);
PAINT MONO (-10610 -540);
FORCEPROP 0 LASTPIN (-10600 -800) $PN 2
R 1
J 2
(-10610 -810);
DISPLAY 0.680851 (-10610 -810);
PAINT MONO (-10610 -810);
FORCEPROP 0 LAST CDS_LOCATION C209
J 0
(-10550 -450);
DISPLAY 1.021277 (-10550 -450);
DISPLAY INVISIBLE (-10550 -450);
FORCEPROP 0 LAST $SEC 1
J 0
(-10550 -450);
DISPLAY 0.680851 (-10550 -450);
PAINT MONO (-10550 -450);
DISPLAY INVISIBLE (-10550 -450);
FORCEPROP 0 LAST CDS_SEC 1
J 0
(-10550 -450);
DISPLAY 1.021277 (-10550 -450);
DISPLAY INVISIBLE (-10550 -450);
FORCEADD CAPACITOR..2
(-10950 -650);
FORCEPROP 1 LAST VALUE 0.1UF
J 0
(-10900 -600);
DISPLAY 1.212766 (-10900 -600);
PAINT GREEN (-10900 -600);
FORCEPROP 0 LAST VOLTAGE 10V
J 0
(-10900 -500);
DISPLAY 1.021277 (-10900 -500);
FORCEPROP 0 LAST PACKAGE 0402
J 0
(-10900 -400);
DISPLAY 1.021277 (-10900 -400);
FORCEPROP 1 LAST PATH I260
J 0
(-11050 -600);
DISPLAY 1.212766 (-11050 -600);
PAINT GREEN (-11050 -600);
DISPLAY INVISIBLE (-11050 -600);
FORCEPROP 1 LAST TOLERANCE 10%
J 0
(-11100 -550);
DISPLAY 1.212766 (-11100 -550);
PAINT GREEN (-11100 -550);
DISPLAY INVISIBLE (-11100 -550);
FORCEPROP 1 LAST CLS_PN G105-0B104-CK
J 0
(-11050 -600);
DISPLAY 1.212766 (-11050 -600);
PAINT GREEN (-11050 -600);
DISPLAY INVISIBLE (-11050 -600);
FORCEPROP 1 LAST CDS_LMAN_SYM_OUTLINE -50,0,50,-50
J 0
(-10950 -650);
DISPLAY 0.468085 (-10950 -650);
PAINT GREEN (-10950 -650);
DISPLAY INVISIBLE (-10950 -650);
FORCEPROP 2 LAST CDS_LIB passive
J 0
(-10950 -650);
DISPLAY INVISIBLE (-10950 -650);
FORCEPROP 1 LAST $LOCATION C205
J 0
(-10900 -800);
DISPLAY 1.212766 (-10900 -800);
PAINT GREEN (-10900 -800);
FORCEPROP 0 LASTPIN (-10950 -550) $PN 1
R 1
J 0
(-10960 -540);
DISPLAY 0.680851 (-10960 -540);
PAINT MONO (-10960 -540);
FORCEPROP 0 LASTPIN (-10950 -800) $PN 2
R 1
J 2
(-10960 -810);
DISPLAY 0.680851 (-10960 -810);
PAINT MONO (-10960 -810);
FORCEPROP 0 LAST CDS_LOCATION C205
J 0
(-10900 -450);
DISPLAY 1.021277 (-10900 -450);
DISPLAY INVISIBLE (-10900 -450);
FORCEPROP 0 LAST $SEC 1
J 0
(-10900 -450);
DISPLAY 0.680851 (-10900 -450);
PAINT MONO (-10900 -450);
DISPLAY INVISIBLE (-10900 -450);
FORCEPROP 0 LAST CDS_SEC 1
J 0
(-10900 -450);
DISPLAY 1.021277 (-10900 -450);
DISPLAY INVISIBLE (-10900 -450);
FORCEADD CAPACITOR..2
(-8650 -650);
FORCEPROP 1 LAST VALUE 47UF
J 0
(-8600 -600);
DISPLAY 1.212766 (-8600 -600);
PAINT GREEN (-8600 -600);
FORCEPROP 0 LAST VOLTAGE 4V
J 0
(-8600 -500);
DISPLAY 1.021277 (-8600 -500);
FORCEPROP 0 LAST PACKAGE 0805
J 0
(-8600 -400);
DISPLAY 1.021277 (-8600 -400);
FORCEPROP 1 LAST PATH I264
J 0
(-8750 -600);
DISPLAY 1.212766 (-8750 -600);
PAINT GREEN (-8750 -600);
DISPLAY INVISIBLE (-8750 -600);
FORCEPROP 1 LAST TOLERANCE 20%
J 0
(-8800 -550);
DISPLAY 1.212766 (-8800 -550);
PAINT GREEN (-8800 -550);
DISPLAY INVISIBLE (-8800 -550);
FORCEPROP 1 LAST CDS_LMAN_SYM_OUTLINE -50,0,50,-50
J 0
(-8650 -650);
DISPLAY 0.468085 (-8650 -650);
PAINT GREEN (-8650 -650);
DISPLAY INVISIBLE (-8650 -650);
FORCEPROP 2 LAST CDS_LIB passive
J 0
(-8650 -650);
DISPLAY INVISIBLE (-8650 -650);
FORCEPROP 1 LAST CLS_PN G107-0F476-AM
J 0
(-8750 -600);
DISPLAY 1.212766 (-8750 -600);
PAINT GREEN (-8750 -600);
DISPLAY INVISIBLE (-8750 -600);
FORCEPROP 1 LAST $LOCATION C125
J 0
(-8600 -800);
DISPLAY 1.212766 (-8600 -800);
PAINT GREEN (-8600 -800);
FORCEPROP 0 LASTPIN (-8650 -550) $PN 1
R 1
J 0
(-8660 -540);
DISPLAY 0.680851 (-8660 -540);
PAINT MONO (-8660 -540);
FORCEPROP 0 LASTPIN (-8650 -800) $PN 2
R 1
J 2
(-8660 -810);
DISPLAY 0.680851 (-8660 -810);
PAINT MONO (-8660 -810);
FORCEPROP 0 LAST CDS_LOCATION C125
J 0
(-8600 -450);
DISPLAY 1.021277 (-8600 -450);
DISPLAY INVISIBLE (-8600 -450);
FORCEPROP 0 LAST $SEC 1
J 0
(-8600 -450);
DISPLAY 0.680851 (-8600 -450);
PAINT MONO (-8600 -450);
DISPLAY INVISIBLE (-8600 -450);
FORCEPROP 0 LAST CDS_SEC 1
J 0
(-8600 -450);
DISPLAY 1.021277 (-8600 -450);
DISPLAY INVISIBLE (-8600 -450);
FORCEADD CAPACITOR..2
(-7550 -650);
FORCEPROP 0 LAST PACKAGE 0805
J 0
(-7500 -400);
DISPLAY 1.021277 (-7500 -400);
FORCEPROP 0 LAST VOLTAGE 4V
J 0
(-7500 -500);
DISPLAY 1.021277 (-7500 -500);
FORCEPROP 1 LAST VALUE 47UF
J 0
(-7500 -600);
DISPLAY 1.212766 (-7500 -600);
PAINT GREEN (-7500 -600);
FORCEPROP 1 LAST PATH I265
J 0
(-7650 -600);
DISPLAY 1.212766 (-7650 -600);
PAINT GREEN (-7650 -600);
DISPLAY INVISIBLE (-7650 -600);
FORCEPROP 1 LAST CDS_LMAN_SYM_OUTLINE -50,0,50,-50
J 0
(-7550 -650);
DISPLAY 0.468085 (-7550 -650);
PAINT GREEN (-7550 -650);
DISPLAY INVISIBLE (-7550 -650);
FORCEPROP 2 LAST CDS_LIB passive
J 0
(-7550 -650);
DISPLAY INVISIBLE (-7550 -650);
FORCEPROP 1 LAST CLS_PN G107-0F476-AM
J 0
(-7650 -600);
DISPLAY 1.212766 (-7650 -600);
PAINT GREEN (-7650 -600);
DISPLAY INVISIBLE (-7650 -600);
FORCEPROP 1 LAST TOLERANCE 20%
J 0
(-7700 -550);
DISPLAY 1.212766 (-7700 -550);
PAINT GREEN (-7700 -550);
DISPLAY INVISIBLE (-7700 -550);
FORCEPROP 1 LAST $LOCATION C143
J 0
(-7500 -800);
DISPLAY 1.212766 (-7500 -800);
PAINT GREEN (-7500 -800);
FORCEPROP 0 LASTPIN (-7550 -550) $PN 1
R 1
J 0
(-7560 -540);
DISPLAY 0.680851 (-7560 -540);
PAINT MONO (-7560 -540);
FORCEPROP 0 LASTPIN (-7550 -800) $PN 2
R 1
J 2
(-7560 -810);
DISPLAY 0.680851 (-7560 -810);
PAINT MONO (-7560 -810);
FORCEPROP 0 LAST CDS_LOCATION C143
J 0
(-7500 -450);
DISPLAY 1.021277 (-7500 -450);
DISPLAY INVISIBLE (-7500 -450);
FORCEPROP 0 LAST $SEC 1
J 0
(-7500 -450);
DISPLAY 0.680851 (-7500 -450);
PAINT MONO (-7500 -450);
DISPLAY INVISIBLE (-7500 -450);
FORCEPROP 0 LAST CDS_SEC 1
J 0
(-7500 -450);
DISPLAY 1.021277 (-7500 -450);
DISPLAY INVISIBLE (-7500 -450);
FORCEADD CAPACITOR..2
(-6750 450);
FORCEPROP 0 LAST VOLTAGE 4V
J 0
(-6700 600);
DISPLAY 1.021277 (-6700 600);
FORCEPROP 1 LAST VALUE 47UF
J 0
(-6700 500);
DISPLAY 1.212766 (-6700 500);
PAINT GREEN (-6700 500);
FORCEPROP 0 LAST PACKAGE 0805
J 0
(-6700 700);
DISPLAY 1.021277 (-6700 700);
FORCEPROP 1 LAST PATH I266
J 0
(-6850 500);
DISPLAY 1.212766 (-6850 500);
PAINT GREEN (-6850 500);
DISPLAY INVISIBLE (-6850 500);
FORCEPROP 1 LAST CLS_PN G107-0F476-AM
J 0
(-6850 500);
DISPLAY 1.212766 (-6850 500);
PAINT GREEN (-6850 500);
DISPLAY INVISIBLE (-6850 500);
FORCEPROP 1 LAST CDS_LMAN_SYM_OUTLINE -50,0,50,-50
J 0
(-6750 450);
DISPLAY 0.468085 (-6750 450);
PAINT GREEN (-6750 450);
DISPLAY INVISIBLE (-6750 450);
FORCEPROP 2 LAST CDS_LIB passive
J 0
(-6750 450);
DISPLAY INVISIBLE (-6750 450);
FORCEPROP 1 LAST TOLERANCE 20%
J 0
(-6900 550);
DISPLAY 1.212766 (-6900 550);
PAINT GREEN (-6900 550);
DISPLAY INVISIBLE (-6900 550);
FORCEPROP 1 LAST $LOCATION C155
J 0
(-6700 300);
DISPLAY 1.212766 (-6700 300);
PAINT GREEN (-6700 300);
FORCEPROP 0 LASTPIN (-6750 550) $PN 1
R 1
J 0
(-6760 560);
DISPLAY 0.680851 (-6760 560);
PAINT MONO (-6760 560);
FORCEPROP 0 LASTPIN (-6750 300) $PN 2
R 1
J 2
(-6760 290);
DISPLAY 0.680851 (-6760 290);
PAINT MONO (-6760 290);
FORCEPROP 0 LAST CDS_LOCATION C155
J 0
(-6700 650);
DISPLAY 1.021277 (-6700 650);
DISPLAY INVISIBLE (-6700 650);
FORCEPROP 0 LAST $SEC 1
J 0
(-6700 650);
DISPLAY 0.680851 (-6700 650);
PAINT MONO (-6700 650);
DISPLAY INVISIBLE (-6700 650);
FORCEPROP 0 LAST CDS_SEC 1
J 0
(-6700 650);
DISPLAY 1.021277 (-6700 650);
DISPLAY INVISIBLE (-6700 650);
FORCEADD CAPACITOR..2
(-5350 2050);
FORCEPROP 0 LAST PACKAGE 0805
J 0
(-5300 2300);
DISPLAY 1.021277 (-5300 2300);
FORCEPROP 0 LAST VOLTAGE 10V
J 0
(-5300 2200);
DISPLAY 1.021277 (-5300 2200);
FORCEPROP 1 LAST VALUE 22UF
J 0
(-5300 2100);
DISPLAY 1.212766 (-5300 2100);
PAINT GREEN (-5300 2100);
FORCEPROP 1 LAST PATH I267
J 0
(-5450 2100);
DISPLAY 1.212766 (-5450 2100);
PAINT GREEN (-5450 2100);
DISPLAY INVISIBLE (-5450 2100);
FORCEPROP 1 LAST CLS_PN G107-0F226-CM
J 0
(-5450 2100);
DISPLAY 1.212766 (-5450 2100);
PAINT GREEN (-5450 2100);
DISPLAY INVISIBLE (-5450 2100);
FORCEPROP 1 LAST TOLERANCE 20%
J 0
(-5500 2150);
DISPLAY 1.212766 (-5500 2150);
PAINT GREEN (-5500 2150);
DISPLAY INVISIBLE (-5500 2150);
FORCEPROP 2 LAST CDS_LIB passive
J 0
(-5350 2050);
DISPLAY INVISIBLE (-5350 2050);
FORCEPROP 1 LAST CDS_LMAN_SYM_OUTLINE -50,0,50,-50
J 0
(-5350 2050);
DISPLAY 0.468085 (-5350 2050);
PAINT GREEN (-5350 2050);
DISPLAY INVISIBLE (-5350 2050);
FORCEPROP 1 LAST $LOCATION C168
J 0
(-5300 1900);
DISPLAY 1.212766 (-5300 1900);
PAINT GREEN (-5300 1900);
FORCEPROP 0 LASTPIN (-5350 2150) $PN 1
R 1
J 0
(-5360 2160);
DISPLAY 0.680851 (-5360 2160);
PAINT MONO (-5360 2160);
FORCEPROP 0 LASTPIN (-5350 1900) $PN 2
R 1
J 2
(-5360 1890);
DISPLAY 0.680851 (-5360 1890);
PAINT MONO (-5360 1890);
FORCEPROP 0 LAST CDS_LOCATION C168
J 0
(-5300 2250);
DISPLAY 1.021277 (-5300 2250);
DISPLAY INVISIBLE (-5300 2250);
FORCEPROP 0 LAST $SEC 1
J 0
(-5300 2250);
DISPLAY 0.680851 (-5300 2250);
PAINT MONO (-5300 2250);
DISPLAY INVISIBLE (-5300 2250);
FORCEPROP 0 LAST CDS_SEC 1
J 0
(-5300 2250);
DISPLAY 1.021277 (-5300 2250);
DISPLAY INVISIBLE (-5300 2250);
FORCEADD CAPACITOR..2
(-5700 2050);
FORCEPROP 1 LAST VALUE 22UF
J 0
(-5650 2100);
DISPLAY 1.212766 (-5650 2100);
PAINT GREEN (-5650 2100);
FORCEPROP 0 LAST PACKAGE 0805
J 0
(-5650 2300);
DISPLAY 1.021277 (-5650 2300);
FORCEPROP 0 LAST VOLTAGE 10V
J 0
(-5650 2200);
DISPLAY 1.021277 (-5650 2200);
FORCEPROP 1 LAST PATH I268
J 0
(-5800 2100);
DISPLAY 1.212766 (-5800 2100);
PAINT GREEN (-5800 2100);
DISPLAY INVISIBLE (-5800 2100);
FORCEPROP 1 LAST CLS_PN G107-0F226-CM
J 0
(-5800 2100);
DISPLAY 1.212766 (-5800 2100);
PAINT GREEN (-5800 2100);
DISPLAY INVISIBLE (-5800 2100);
FORCEPROP 1 LAST TOLERANCE 20%
J 0
(-5850 2150);
DISPLAY 1.212766 (-5850 2150);
PAINT GREEN (-5850 2150);
DISPLAY INVISIBLE (-5850 2150);
FORCEPROP 1 LAST CDS_LMAN_SYM_OUTLINE -50,0,50,-50
J 0
(-5700 2050);
DISPLAY 0.468085 (-5700 2050);
PAINT GREEN (-5700 2050);
DISPLAY INVISIBLE (-5700 2050);
FORCEPROP 2 LAST CDS_LIB passive
J 0
(-5700 2050);
DISPLAY INVISIBLE (-5700 2050);
FORCEPROP 1 LAST $LOCATION C164
J 0
(-5650 1900);
DISPLAY 1.212766 (-5650 1900);
PAINT GREEN (-5650 1900);
FORCEPROP 0 LASTPIN (-5700 2150) $PN 1
R 1
J 0
(-5710 2160);
DISPLAY 0.680851 (-5710 2160);
PAINT MONO (-5710 2160);
FORCEPROP 0 LASTPIN (-5700 1900) $PN 2
R 1
J 2
(-5710 1890);
DISPLAY 0.680851 (-5710 1890);
PAINT MONO (-5710 1890);
FORCEPROP 0 LAST CDS_LOCATION C164
J 0
(-5650 2250);
DISPLAY 1.021277 (-5650 2250);
DISPLAY INVISIBLE (-5650 2250);
FORCEPROP 0 LAST $SEC 1
J 0
(-5650 2250);
DISPLAY 0.680851 (-5650 2250);
PAINT MONO (-5650 2250);
DISPLAY INVISIBLE (-5650 2250);
FORCEPROP 0 LAST CDS_SEC 1
J 0
(-5650 2250);
DISPLAY 1.021277 (-5650 2250);
DISPLAY INVISIBLE (-5650 2250);
FORCEADD CAPACITOR..2
(-6750 4300);
FORCEPROP 1 LAST VALUE 4.7UF
J 0
(-6700 4350);
DISPLAY 1.212766 (-6700 4350);
PAINT GREEN (-6700 4350);
FORCEPROP 0 LAST VOLTAGE 6.3V
J 0
(-6700 4450);
DISPLAY 1.021277 (-6700 4450);
FORCEPROP 0 LAST PACKAGE 0402
J 0
(-6700 4550);
DISPLAY 1.021277 (-6700 4550);
FORCEPROP 1 LAST PATH I270
J 0
(-6850 4350);
DISPLAY 1.212766 (-6850 4350);
PAINT GREEN (-6850 4350);
DISPLAY INVISIBLE (-6850 4350);
FORCEPROP 2 LAST CDS_LIB passive
J 0
(-6750 4300);
DISPLAY INVISIBLE (-6750 4300);
FORCEPROP 1 LAST CDS_LMAN_SYM_OUTLINE -50,0,50,-50
J 0
(-6750 4300);
DISPLAY 0.468085 (-6750 4300);
PAINT GREEN (-6750 4300);
DISPLAY INVISIBLE (-6750 4300);
FORCEPROP 1 LAST CLS_PN G105-0F475-BM
J 0
(-6850 4350);
DISPLAY 1.212766 (-6850 4350);
PAINT GREEN (-6850 4350);
DISPLAY INVISIBLE (-6850 4350);
FORCEPROP 1 LAST TOLERANCE 20%
J 0
(-6900 4400);
DISPLAY 1.212766 (-6900 4400);
PAINT GREEN (-6900 4400);
DISPLAY INVISIBLE (-6900 4400);
FORCEPROP 1 LAST $LOCATION C154
J 0
(-6700 4150);
DISPLAY 1.212766 (-6700 4150);
PAINT GREEN (-6700 4150);
FORCEPROP 0 LASTPIN (-6750 4400) $PN 1
R 1
J 0
(-6760 4410);
DISPLAY 0.680851 (-6760 4410);
PAINT MONO (-6760 4410);
FORCEPROP 0 LASTPIN (-6750 4150) $PN 2
R 1
J 2
(-6760 4140);
DISPLAY 0.680851 (-6760 4140);
PAINT MONO (-6760 4140);
FORCEPROP 0 LAST CDS_LOCATION C154
J 0
(-6700 4500);
DISPLAY 1.021277 (-6700 4500);
DISPLAY INVISIBLE (-6700 4500);
FORCEPROP 0 LAST $SEC 1
J 0
(-6700 4500);
DISPLAY 0.680851 (-6700 4500);
PAINT MONO (-6700 4500);
DISPLAY INVISIBLE (-6700 4500);
FORCEPROP 0 LAST CDS_SEC 1
J 0
(-6700 4500);
DISPLAY 1.021277 (-6700 4500);
DISPLAY INVISIBLE (-6700 4500);
FORCEADD CAPACITOR..2
(-6400 4300);
FORCEPROP 0 LAST VOLTAGE 6.3V
J 0
(-6350 4450);
DISPLAY 1.021277 (-6350 4450);
FORCEPROP 1 LAST VALUE 4.7UF
J 0
(-6350 4350);
DISPLAY 1.212766 (-6350 4350);
PAINT GREEN (-6350 4350);
FORCEPROP 0 LAST PACKAGE 0402
J 0
(-6350 4550);
DISPLAY 1.021277 (-6350 4550);
FORCEPROP 1 LAST PATH I271
J 0
(-6500 4350);
DISPLAY 1.212766 (-6500 4350);
PAINT GREEN (-6500 4350);
DISPLAY INVISIBLE (-6500 4350);
FORCEPROP 1 LAST TOLERANCE 20%
J 0
(-6550 4400);
DISPLAY 1.212766 (-6550 4400);
PAINT GREEN (-6550 4400);
DISPLAY INVISIBLE (-6550 4400);
FORCEPROP 2 LAST CDS_LIB passive
J 0
(-6400 4300);
DISPLAY INVISIBLE (-6400 4300);
FORCEPROP 1 LAST CDS_LMAN_SYM_OUTLINE -50,0,50,-50
J 0
(-6400 4300);
DISPLAY 0.468085 (-6400 4300);
PAINT GREEN (-6400 4300);
DISPLAY INVISIBLE (-6400 4300);
FORCEPROP 1 LAST CLS_PN G105-0F475-BM
J 0
(-6500 4350);
DISPLAY 1.212766 (-6500 4350);
PAINT GREEN (-6500 4350);
DISPLAY INVISIBLE (-6500 4350);
FORCEPROP 1 LAST $LOCATION C159
J 0
(-6350 4150);
DISPLAY 1.212766 (-6350 4150);
PAINT GREEN (-6350 4150);
FORCEPROP 0 LASTPIN (-6400 4400) $PN 1
R 1
J 0
(-6410 4410);
DISPLAY 0.680851 (-6410 4410);
PAINT MONO (-6410 4410);
FORCEPROP 0 LASTPIN (-6400 4150) $PN 2
R 1
J 2
(-6410 4140);
DISPLAY 0.680851 (-6410 4140);
PAINT MONO (-6410 4140);
FORCEPROP 0 LAST CDS_LOCATION C159
J 0
(-6350 4500);
DISPLAY 1.021277 (-6350 4500);
DISPLAY INVISIBLE (-6350 4500);
FORCEPROP 0 LAST $SEC 1
J 0
(-6350 4500);
DISPLAY 0.680851 (-6350 4500);
PAINT MONO (-6350 4500);
DISPLAY INVISIBLE (-6350 4500);
FORCEPROP 0 LAST CDS_SEC 1
J 0
(-6350 4500);
DISPLAY 1.021277 (-6350 4500);
DISPLAY INVISIBLE (-6350 4500);
FORCEADD CAPACITOR..2
(-6050 4300);
FORCEPROP 0 LAST VOLTAGE 6.3V
J 0
(-6000 4450);
DISPLAY 1.021277 (-6000 4450);
FORCEPROP 1 LAST VALUE 4.7UF
J 0
(-6000 4350);
DISPLAY 1.212766 (-6000 4350);
PAINT GREEN (-6000 4350);
FORCEPROP 0 LAST PACKAGE 0402
J 0
(-6000 4550);
DISPLAY 1.021277 (-6000 4550);
FORCEPROP 1 LAST PATH I272
J 0
(-6150 4350);
DISPLAY 1.212766 (-6150 4350);
PAINT GREEN (-6150 4350);
DISPLAY INVISIBLE (-6150 4350);
FORCEPROP 1 LAST TOLERANCE 20%
J 0
(-6200 4400);
DISPLAY 1.212766 (-6200 4400);
PAINT GREEN (-6200 4400);
DISPLAY INVISIBLE (-6200 4400);
FORCEPROP 2 LAST CDS_LIB passive
J 0
(-6050 4300);
DISPLAY INVISIBLE (-6050 4300);
FORCEPROP 1 LAST CDS_LMAN_SYM_OUTLINE -50,0,50,-50
J 0
(-6050 4300);
DISPLAY 0.468085 (-6050 4300);
PAINT GREEN (-6050 4300);
DISPLAY INVISIBLE (-6050 4300);
FORCEPROP 1 LAST CLS_PN G105-0F475-BM
J 0
(-6150 4350);
DISPLAY 1.212766 (-6150 4350);
PAINT GREEN (-6150 4350);
DISPLAY INVISIBLE (-6150 4350);
FORCEPROP 1 LAST $LOCATION C163
J 0
(-6000 4150);
DISPLAY 1.212766 (-6000 4150);
PAINT GREEN (-6000 4150);
FORCEPROP 0 LASTPIN (-6050 4400) $PN 1
R 1
J 0
(-6060 4410);
DISPLAY 0.680851 (-6060 4410);
PAINT MONO (-6060 4410);
FORCEPROP 0 LASTPIN (-6050 4150) $PN 2
R 1
J 2
(-6060 4140);
DISPLAY 0.680851 (-6060 4140);
PAINT MONO (-6060 4140);
FORCEPROP 0 LAST CDS_LOCATION C163
J 0
(-6000 4500);
DISPLAY 1.021277 (-6000 4500);
DISPLAY INVISIBLE (-6000 4500);
FORCEPROP 0 LAST $SEC 1
J 0
(-6000 4500);
DISPLAY 0.680851 (-6000 4500);
PAINT MONO (-6000 4500);
DISPLAY INVISIBLE (-6000 4500);
FORCEPROP 0 LAST CDS_SEC 1
J 0
(-6000 4500);
DISPLAY 1.021277 (-6000 4500);
DISPLAY INVISIBLE (-6000 4500);
FORCEADD CAPACITOR..2
(-5700 4300);
FORCEPROP 0 LAST PACKAGE 0402
J 0
(-5650 4550);
DISPLAY 1.021277 (-5650 4550);
FORCEPROP 1 LAST VALUE 4.7UF
J 0
(-5650 4350);
DISPLAY 1.212766 (-5650 4350);
PAINT GREEN (-5650 4350);
FORCEPROP 0 LAST VOLTAGE 6.3V
J 0
(-5650 4450);
DISPLAY 1.021277 (-5650 4450);
FORCEPROP 1 LAST PATH I273
J 0
(-5800 4350);
DISPLAY 1.212766 (-5800 4350);
PAINT GREEN (-5800 4350);
DISPLAY INVISIBLE (-5800 4350);
FORCEPROP 1 LAST TOLERANCE 20%
J 0
(-5850 4400);
DISPLAY 1.212766 (-5850 4400);
PAINT GREEN (-5850 4400);
DISPLAY INVISIBLE (-5850 4400);
FORCEPROP 1 LAST CLS_PN G105-0F475-BM
J 0
(-5800 4350);
DISPLAY 1.212766 (-5800 4350);
PAINT GREEN (-5800 4350);
DISPLAY INVISIBLE (-5800 4350);
FORCEPROP 1 LAST CDS_LMAN_SYM_OUTLINE -50,0,50,-50
J 0
(-5700 4300);
DISPLAY 0.468085 (-5700 4300);
PAINT GREEN (-5700 4300);
DISPLAY INVISIBLE (-5700 4300);
FORCEPROP 2 LAST CDS_LIB passive
J 0
(-5700 4300);
DISPLAY INVISIBLE (-5700 4300);
FORCEPROP 1 LAST $LOCATION C167
J 0
(-5650 4150);
DISPLAY 1.212766 (-5650 4150);
PAINT GREEN (-5650 4150);
FORCEPROP 0 LASTPIN (-5700 4400) $PN 1
R 1
J 0
(-5710 4410);
DISPLAY 0.680851 (-5710 4410);
PAINT MONO (-5710 4410);
FORCEPROP 0 LASTPIN (-5700 4150) $PN 2
R 1
J 2
(-5710 4140);
DISPLAY 0.680851 (-5710 4140);
PAINT MONO (-5710 4140);
FORCEPROP 0 LAST CDS_LOCATION C167
J 0
(-5650 4500);
DISPLAY 1.021277 (-5650 4500);
DISPLAY INVISIBLE (-5650 4500);
FORCEPROP 0 LAST $SEC 1
J 0
(-5650 4500);
DISPLAY 0.680851 (-5650 4500);
PAINT MONO (-5650 4500);
DISPLAY INVISIBLE (-5650 4500);
FORCEPROP 0 LAST CDS_SEC 1
J 0
(-5650 4500);
DISPLAY 1.021277 (-5650 4500);
DISPLAY INVISIBLE (-5650 4500);
FORCEADD CAPACITOR..2
(-2400 5700);
FORCEPROP 1 LAST VALUE 47UF
J 0
(-2350 5750);
DISPLAY 1.212766 (-2350 5750);
PAINT GREEN (-2350 5750);
FORCEPROP 0 LAST VOLTAGE 4V
J 0
(-2350 5850);
DISPLAY 1.021277 (-2350 5850);
FORCEPROP 0 LAST PACKAGE 0805
J 0
(-2250 5650);
DISPLAY 1.021277 (-2250 5650);
FORCEPROP 1 LAST PATH I274
J 0
(-2500 5750);
DISPLAY 1.212766 (-2500 5750);
PAINT GREEN (-2500 5750);
DISPLAY INVISIBLE (-2500 5750);
FORCEPROP 2 LAST CDS_LIB passive
J 0
(-2400 5700);
DISPLAY INVISIBLE (-2400 5700);
FORCEPROP 1 LAST CDS_LMAN_SYM_OUTLINE -50,0,50,-50
J 0
(-2400 5700);
DISPLAY 0.468085 (-2400 5700);
PAINT GREEN (-2400 5700);
DISPLAY INVISIBLE (-2400 5700);
FORCEPROP 1 LAST CLS_PN G107-0F476-AM
J 0
(-2500 5750);
DISPLAY 1.212766 (-2500 5750);
PAINT GREEN (-2500 5750);
DISPLAY INVISIBLE (-2500 5750);
FORCEPROP 1 LAST TOLERANCE 20%
J 0
(-2550 5800);
DISPLAY 1.212766 (-2550 5800);
PAINT GREEN (-2550 5800);
DISPLAY INVISIBLE (-2550 5800);
FORCEPROP 1 LAST $LOCATION C179
J 0
(-2350 5550);
DISPLAY 1.212766 (-2350 5550);
PAINT GREEN (-2350 5550);
FORCEPROP 0 LASTPIN (-2400 5800) $PN 1
R 1
J 0
(-2410 5810);
DISPLAY 0.680851 (-2410 5810);
PAINT MONO (-2410 5810);
FORCEPROP 0 LASTPIN (-2400 5550) $PN 2
R 1
J 2
(-2410 5540);
DISPLAY 0.680851 (-2410 5540);
PAINT MONO (-2410 5540);
FORCEPROP 0 LAST CDS_LOCATION C179
J 0
(-2350 5900);
DISPLAY 1.021277 (-2350 5900);
DISPLAY INVISIBLE (-2350 5900);
FORCEPROP 0 LAST $SEC 1
J 0
(-2350 5900);
DISPLAY 0.680851 (-2350 5900);
PAINT MONO (-2350 5900);
DISPLAY INVISIBLE (-2350 5900);
FORCEPROP 0 LAST CDS_SEC 1
J 0
(-2350 5900);
DISPLAY 1.021277 (-2350 5900);
DISPLAY INVISIBLE (-2350 5900);
FORCEADD CAPACITOR..2
(-7900 7150);
FORCEPROP 0 LAST VOLTAGE 6.3V
J 0
(-7850 7300);
DISPLAY 1.021277 (-7850 7300);
FORCEPROP 1 LAST VALUE 4.7UF
J 0
(-7850 7200);
DISPLAY 1.212766 (-7850 7200);
PAINT GREEN (-7850 7200);
FORCEPROP 0 LAST PACKAGE 0402
J 0
(-7850 7400);
DISPLAY 1.021277 (-7850 7400);
FORCEPROP 1 LAST PATH I275
J 0
(-8000 7200);
DISPLAY 1.212766 (-8000 7200);
PAINT GREEN (-8000 7200);
DISPLAY INVISIBLE (-8000 7200);
FORCEPROP 1 LAST TOLERANCE 20%
J 0
(-8050 7250);
DISPLAY 1.212766 (-8050 7250);
PAINT GREEN (-8050 7250);
DISPLAY INVISIBLE (-8050 7250);
FORCEPROP 2 LAST CDS_LIB passive
J 0
(-7900 7150);
DISPLAY INVISIBLE (-7900 7150);
FORCEPROP 1 LAST CDS_LMAN_SYM_OUTLINE -50,0,50,-50
J 0
(-7900 7150);
DISPLAY 0.468085 (-7900 7150);
PAINT GREEN (-7900 7150);
DISPLAY INVISIBLE (-7900 7150);
FORCEPROP 1 LAST CLS_PN G105-0F475-BM
J 0
(-8000 7200);
DISPLAY 1.212766 (-8000 7200);
PAINT GREEN (-8000 7200);
DISPLAY INVISIBLE (-8000 7200);
FORCEPROP 1 LAST $LOCATION C138
J 0
(-7850 7000);
DISPLAY 1.212766 (-7850 7000);
PAINT GREEN (-7850 7000);
FORCEPROP 0 LASTPIN (-7900 7250) $PN 1
R 1
J 0
(-7910 7260);
DISPLAY 0.680851 (-7910 7260);
PAINT MONO (-7910 7260);
FORCEPROP 0 LASTPIN (-7900 7000) $PN 2
R 1
J 2
(-7910 6990);
DISPLAY 0.680851 (-7910 6990);
PAINT MONO (-7910 6990);
FORCEPROP 0 LAST CDS_LOCATION C138
J 0
(-7850 7350);
DISPLAY 1.021277 (-7850 7350);
DISPLAY INVISIBLE (-7850 7350);
FORCEPROP 0 LAST $SEC 1
J 0
(-7850 7350);
DISPLAY 0.680851 (-7850 7350);
PAINT MONO (-7850 7350);
DISPLAY INVISIBLE (-7850 7350);
FORCEPROP 0 LAST CDS_SEC 1
J 0
(-7850 7350);
DISPLAY 1.021277 (-7850 7350);
DISPLAY INVISIBLE (-7850 7350);
FORCEADD CAPACITOR..2
(-6900 7150);
FORCEPROP 1 LAST VALUE 0.1UF
J 0
(-6850 7200);
DISPLAY 1.212766 (-6850 7200);
PAINT GREEN (-6850 7200);
FORCEPROP 0 LAST VOLTAGE 10V
J 0
(-6850 7300);
DISPLAY 1.021277 (-6850 7300);
FORCEPROP 0 LAST PACKAGE 0402
J 0
(-6850 7400);
DISPLAY 1.021277 (-6850 7400);
FORCEPROP 1 LAST PATH I276
J 0
(-7000 7200);
DISPLAY 1.212766 (-7000 7200);
PAINT GREEN (-7000 7200);
DISPLAY INVISIBLE (-7000 7200);
FORCEPROP 1 LAST TOLERANCE 10%
J 0
(-7050 7250);
DISPLAY 1.212766 (-7050 7250);
PAINT GREEN (-7050 7250);
DISPLAY INVISIBLE (-7050 7250);
FORCEPROP 2 LAST CDS_LIB passive
J 0
(-6900 7150);
DISPLAY INVISIBLE (-6900 7150);
FORCEPROP 1 LAST CDS_LMAN_SYM_OUTLINE -50,0,50,-50
J 0
(-6900 7150);
DISPLAY 0.468085 (-6900 7150);
PAINT GREEN (-6900 7150);
DISPLAY INVISIBLE (-6900 7150);
FORCEPROP 1 LAST CLS_PN G105-0B104-CK
J 0
(-7000 7200);
DISPLAY 1.212766 (-7000 7200);
PAINT GREEN (-7000 7200);
DISPLAY INVISIBLE (-7000 7200);
FORCEPROP 1 LAST $LOCATION C150
J 0
(-6850 7000);
DISPLAY 1.212766 (-6850 7000);
PAINT GREEN (-6850 7000);
FORCEPROP 0 LASTPIN (-6900 7250) $PN 1
R 1
J 0
(-6910 7260);
DISPLAY 0.680851 (-6910 7260);
PAINT MONO (-6910 7260);
FORCEPROP 0 LASTPIN (-6900 7000) $PN 2
R 1
J 2
(-6910 6990);
DISPLAY 0.680851 (-6910 6990);
PAINT MONO (-6910 6990);
FORCEPROP 0 LAST CDS_LOCATION C150
J 0
(-6850 7350);
DISPLAY 1.021277 (-6850 7350);
DISPLAY INVISIBLE (-6850 7350);
FORCEPROP 0 LAST $SEC 1
J 0
(-6850 7350);
DISPLAY 0.680851 (-6850 7350);
PAINT MONO (-6850 7350);
DISPLAY INVISIBLE (-6850 7350);
FORCEPROP 0 LAST CDS_SEC 1
J 0
(-6850 7350);
DISPLAY 1.021277 (-6850 7350);
DISPLAY INVISIBLE (-6850 7350);
FORCEADD CAPACITOR..2
(-3600 5700);
FORCEPROP 1 LAST VALUE 100UF
J 0
(-3550 5750);
DISPLAY 1.212766 (-3550 5750);
PAINT GREEN (-3550 5750);
FORCEPROP 0 LAST PACKAGE 1210
J 0
(-3500 5650);
DISPLAY 1.021277 (-3500 5650);
FORCEPROP 0 LAST VOLTAGE 6.3V
J 0
(-3550 5850);
DISPLAY 1.021277 (-3550 5850);
FORCEPROP 1 LAST PATH I277
J 0
(-3700 5750);
DISPLAY 1.212766 (-3700 5750);
PAINT GREEN (-3700 5750);
DISPLAY INVISIBLE (-3700 5750);
FORCEPROP 1 LAST TOLERANCE 20%
J 0
(-3750 5800);
DISPLAY 1.212766 (-3750 5800);
PAINT GREEN (-3750 5800);
DISPLAY INVISIBLE (-3750 5800);
FORCEPROP 1 LAST CLS_PN G109-0G107-BM
J 0
(-3700 5750);
DISPLAY 1.212766 (-3700 5750);
PAINT GREEN (-3700 5750);
DISPLAY INVISIBLE (-3700 5750);
FORCEPROP 1 LAST CDS_LMAN_SYM_OUTLINE -50,0,50,-50
J 0
(-3600 5700);
DISPLAY 0.468085 (-3600 5700);
PAINT GREEN (-3600 5700);
DISPLAY INVISIBLE (-3600 5700);
FORCEPROP 2 LAST CDS_LIB passive
J 0
(-3600 5700);
DISPLAY INVISIBLE (-3600 5700);
FORCEPROP 1 LAST $LOCATION C177
J 0
(-3550 5550);
DISPLAY 1.212766 (-3550 5550);
PAINT GREEN (-3550 5550);
FORCEPROP 0 LASTPIN (-3600 5800) $PN 1
R 1
J 0
(-3610 5810);
DISPLAY 0.680851 (-3610 5810);
PAINT MONO (-3610 5810);
FORCEPROP 0 LASTPIN (-3600 5550) $PN 2
R 1
J 2
(-3610 5540);
DISPLAY 0.680851 (-3610 5540);
PAINT MONO (-3610 5540);
FORCEPROP 0 LAST CDS_LOCATION C177
J 0
(-3550 5900);
DISPLAY 1.021277 (-3550 5900);
DISPLAY INVISIBLE (-3550 5900);
FORCEPROP 0 LAST $SEC 1
J 0
(-3550 5900);
DISPLAY 0.680851 (-3550 5900);
PAINT MONO (-3550 5900);
DISPLAY INVISIBLE (-3550 5900);
FORCEPROP 0 LAST CDS_SEC 1
J 0
(-3550 5900);
DISPLAY 1.021277 (-3550 5900);
DISPLAY INVISIBLE (-3550 5900);
FORCEADD CAPACITOR..2
(-4650 5700);
FORCEPROP 1 LAST VALUE 47UF
J 0
(-4600 5750);
DISPLAY 1.212766 (-4600 5750);
PAINT GREEN (-4600 5750);
FORCEPROP 0 LAST PACKAGE 0805
J 0
(-4600 5950);
DISPLAY 1.021277 (-4600 5950);
FORCEPROP 0 LAST VOLTAGE 4V
J 0
(-4600 5850);
DISPLAY 1.021277 (-4600 5850);
FORCEPROP 1 LAST PATH I280
J 0
(-4750 5750);
DISPLAY 1.212766 (-4750 5750);
PAINT GREEN (-4750 5750);
DISPLAY INVISIBLE (-4750 5750);
FORCEPROP 1 LAST CLS_PN G107-0F476-AM
J 0
(-4750 5750);
DISPLAY 1.212766 (-4750 5750);
PAINT GREEN (-4750 5750);
DISPLAY INVISIBLE (-4750 5750);
FORCEPROP 1 LAST CDS_LMAN_SYM_OUTLINE -50,0,50,-50
J 0
(-4650 5700);
DISPLAY 0.468085 (-4650 5700);
PAINT GREEN (-4650 5700);
DISPLAY INVISIBLE (-4650 5700);
FORCEPROP 2 LAST CDS_LIB passive
J 0
(-4650 5700);
DISPLAY INVISIBLE (-4650 5700);
FORCEPROP 1 LAST TOLERANCE 20%
J 0
(-4800 5800);
DISPLAY 1.212766 (-4800 5800);
PAINT GREEN (-4800 5800);
DISPLAY INVISIBLE (-4800 5800);
FORCEPROP 1 LAST $LOCATION C173
J 0
(-4600 5550);
DISPLAY 1.212766 (-4600 5550);
PAINT GREEN (-4600 5550);
FORCEPROP 0 LASTPIN (-4650 5800) $PN 1
R 1
J 0
(-4660 5810);
DISPLAY 0.680851 (-4660 5810);
PAINT MONO (-4660 5810);
FORCEPROP 0 LASTPIN (-4650 5550) $PN 2
R 1
J 2
(-4660 5540);
DISPLAY 0.680851 (-4660 5540);
PAINT MONO (-4660 5540);
FORCEPROP 0 LAST CDS_LOCATION C173
J 0
(-4600 5900);
DISPLAY 1.021277 (-4600 5900);
DISPLAY INVISIBLE (-4600 5900);
FORCEPROP 0 LAST $SEC 1
J 0
(-4600 5900);
DISPLAY 0.680851 (-4600 5900);
PAINT MONO (-4600 5900);
DISPLAY INVISIBLE (-4600 5900);
FORCEPROP 0 LAST CDS_SEC 1
J 0
(-4600 5900);
DISPLAY 1.021277 (-4600 5900);
DISPLAY INVISIBLE (-4600 5900);
FORCEADD CAPACITOR..2
(-7950 450);
FORCEPROP 0 LAST VOLTAGE 4V
J 0
(-7900 600);
DISPLAY 1.021277 (-7900 600);
FORCEPROP 1 LAST VALUE 47UF
J 0
(-7900 500);
DISPLAY 1.212766 (-7900 500);
PAINT GREEN (-7900 500);
FORCEPROP 1 LAST PATH I281
J 0
(-8050 500);
DISPLAY 1.212766 (-8050 500);
PAINT GREEN (-8050 500);
DISPLAY INVISIBLE (-8050 500);
FORCEPROP 1 LAST TOLERANCE 20%
J 0
(-8100 550);
DISPLAY 1.212766 (-8100 550);
PAINT GREEN (-8100 550);
DISPLAY INVISIBLE (-8100 550);
FORCEPROP 1 LAST CLS_PN G107-0F476-AM
J 0
(-8050 500);
DISPLAY 1.212766 (-8050 500);
PAINT GREEN (-8050 500);
DISPLAY INVISIBLE (-8050 500);
FORCEPROP 2 LAST CDS_LIB passive
J 0
(-7950 450);
DISPLAY INVISIBLE (-7950 450);
FORCEPROP 1 LAST CDS_LMAN_SYM_OUTLINE -50,0,50,-50
J 0
(-7950 450);
DISPLAY 0.468085 (-7950 450);
PAINT GREEN (-7950 450);
DISPLAY INVISIBLE (-7950 450);
FORCEPROP 1 LAST $LOCATION C137
J 0
(-7900 300);
DISPLAY 1.212766 (-7900 300);
PAINT GREEN (-7900 300);
FORCEPROP 0 LASTPIN (-7950 550) $PN 1
R 1
J 0
(-7960 560);
DISPLAY 0.680851 (-7960 560);
PAINT MONO (-7960 560);
FORCEPROP 0 LASTPIN (-7950 300) $PN 2
R 1
J 2
(-7960 290);
DISPLAY 0.680851 (-7960 290);
PAINT MONO (-7960 290);
FORCEPROP 0 LAST CDS_LOCATION C137
J 0
(-7900 650);
DISPLAY 1.021277 (-7900 650);
DISPLAY INVISIBLE (-7900 650);
FORCEPROP 0 LAST $SEC 1
J 0
(-7900 650);
DISPLAY 0.680851 (-7900 650);
PAINT MONO (-7900 650);
DISPLAY INVISIBLE (-7900 650);
FORCEPROP 0 LAST CDS_SEC 1
J 0
(-7900 650);
DISPLAY 1.021277 (-7900 650);
DISPLAY INVISIBLE (-7900 650);
FORCEADD CAPACITOR..2
(-5350 4300);
FORCEPROP 1 LAST VALUE 4.7UF
J 0
(-5300 4350);
DISPLAY 1.212766 (-5300 4350);
PAINT GREEN (-5300 4350);
FORCEPROP 0 LAST PACKAGE 0402
J 0
(-5300 4550);
DISPLAY 1.021277 (-5300 4550);
FORCEPROP 0 LAST VOLTAGE 6.3V
J 0
(-5300 4450);
DISPLAY 1.021277 (-5300 4450);
FORCEPROP 1 LAST PATH I282
J 0
(-5450 4350);
DISPLAY 1.212766 (-5450 4350);
PAINT GREEN (-5450 4350);
DISPLAY INVISIBLE (-5450 4350);
FORCEPROP 1 LAST TOLERANCE 20%
J 0
(-5500 4400);
DISPLAY 1.212766 (-5500 4400);
PAINT GREEN (-5500 4400);
DISPLAY INVISIBLE (-5500 4400);
FORCEPROP 2 LAST CDS_LIB passive
J 0
(-5350 4300);
DISPLAY INVISIBLE (-5350 4300);
FORCEPROP 1 LAST CDS_LMAN_SYM_OUTLINE -50,0,50,-50
J 0
(-5350 4300);
DISPLAY 0.468085 (-5350 4300);
PAINT GREEN (-5350 4300);
DISPLAY INVISIBLE (-5350 4300);
FORCEPROP 1 LAST CLS_PN G105-0F475-BM
J 0
(-5450 4350);
DISPLAY 1.212766 (-5450 4350);
PAINT GREEN (-5450 4350);
DISPLAY INVISIBLE (-5450 4350);
FORCEPROP 1 LAST $LOCATION C170
J 0
(-5300 4150);
DISPLAY 1.212766 (-5300 4150);
PAINT GREEN (-5300 4150);
FORCEPROP 0 LASTPIN (-5350 4400) $PN 1
R 1
J 0
(-5360 4410);
DISPLAY 0.680851 (-5360 4410);
PAINT MONO (-5360 4410);
FORCEPROP 0 LASTPIN (-5350 4150) $PN 2
R 1
J 2
(-5360 4140);
DISPLAY 0.680851 (-5360 4140);
PAINT MONO (-5360 4140);
FORCEPROP 0 LAST CDS_LOCATION C170
J 0
(-5300 4500);
DISPLAY 1.021277 (-5300 4500);
DISPLAY INVISIBLE (-5300 4500);
FORCEPROP 0 LAST $SEC 1
J 0
(-5300 4500);
DISPLAY 0.680851 (-5300 4500);
PAINT MONO (-5300 4500);
DISPLAY INVISIBLE (-5300 4500);
FORCEPROP 0 LAST CDS_SEC 1
J 0
(-5300 4500);
DISPLAY 1.021277 (-5300 4500);
DISPLAY INVISIBLE (-5300 4500);
FORCEADD CAPACITOR..2
(-2950 5700);
FORCEPROP 1 LAST VALUE 0.1UF
J 0
(-2900 5750);
DISPLAY 1.212766 (-2900 5750);
PAINT GREEN (-2900 5750);
FORCEPROP 0 LAST VOLTAGE 10V
J 0
(-2900 5850);
DISPLAY 1.021277 (-2900 5850);
FORCEPROP 0 LAST PACKAGE 0402
J 0
(-2850 5650);
DISPLAY 1.021277 (-2850 5650);
FORCEPROP 1 LAST PATH I283
J 0
(-3050 5750);
DISPLAY 1.212766 (-3050 5750);
PAINT GREEN (-3050 5750);
DISPLAY INVISIBLE (-3050 5750);
FORCEPROP 1 LAST TOLERANCE 10%
J 0
(-3100 5800);
DISPLAY 1.212766 (-3100 5800);
PAINT GREEN (-3100 5800);
DISPLAY INVISIBLE (-3100 5800);
FORCEPROP 1 LAST CLS_PN G105-0B104-CK
J 0
(-3050 5750);
DISPLAY 1.212766 (-3050 5750);
PAINT GREEN (-3050 5750);
DISPLAY INVISIBLE (-3050 5750);
FORCEPROP 1 LAST CDS_LMAN_SYM_OUTLINE -50,0,50,-50
J 0
(-2950 5700);
DISPLAY 0.468085 (-2950 5700);
PAINT GREEN (-2950 5700);
DISPLAY INVISIBLE (-2950 5700);
FORCEPROP 2 LAST CDS_LIB passive
J 0
(-2950 5700);
DISPLAY INVISIBLE (-2950 5700);
FORCEPROP 1 LAST $LOCATION C178
J 0
(-2900 5550);
DISPLAY 1.212766 (-2900 5550);
PAINT GREEN (-2900 5550);
FORCEPROP 0 LASTPIN (-2950 5800) $PN 1
R 1
J 0
(-2960 5810);
DISPLAY 0.680851 (-2960 5810);
PAINT MONO (-2960 5810);
FORCEPROP 0 LASTPIN (-2950 5550) $PN 2
R 1
J 2
(-2960 5540);
DISPLAY 0.680851 (-2960 5540);
PAINT MONO (-2960 5540);
FORCEPROP 0 LAST CDS_LOCATION C178
J 0
(-2900 5900);
DISPLAY 1.021277 (-2900 5900);
DISPLAY INVISIBLE (-2900 5900);
FORCEPROP 0 LAST $SEC 1
J 0
(-2900 5900);
DISPLAY 0.680851 (-2900 5900);
PAINT MONO (-2900 5900);
DISPLAY INVISIBLE (-2900 5900);
FORCEPROP 0 LAST CDS_SEC 1
J 0
(-2900 5900);
DISPLAY 1.021277 (-2900 5900);
DISPLAY INVISIBLE (-2900 5900);
FORCEADD VCC..1
(-4300 4700);
FORCEPROP 3 LASTPIN (-4250 4650) SIG_NAME XP3R3V_FPGA\g
J 0
(-4240 4660);
DISPLAY 0.659574 (-4240 4660);
PAINT MONO (-4240 4660);
DISPLAY INVISIBLE (-4240 4660);
FORCEPROP 1 LAST HDL_POWER XP3R3V_FPGA
J 1
(-4245 4755);
DISPLAY 1.021277 (-4245 4755);
PAINT GREEN (-4245 4755);
FORCEPROP 0 LAST VOLTAGE 3.3V
J 0
(-4550 4850);
DISPLAY 1.021277 (-4550 4850);
DISPLAY BOTH (-4550 4850);
FORCEPROP 1 LAST PATH I284
J 0
(-4265 4790);
DISPLAY 0.808511 (-4265 4790);
PAINT GREEN (-4265 4790);
DISPLAY INVISIBLE (-4265 4790);
FORCEPROP 1 LAST BODY_TYPE PLUMBING
J 0
(-4345 4657);
DISPLAY 0.340426 (-4345 4657);
PAINT GREEN (-4345 4657);
DISPLAY INVISIBLE (-4345 4657);
FORCEPROP 1 LAST CDS_LMAN_SYM_OUTLINE -250,250,250,-250
J 0
(-4300 4700);
DISPLAY 0.468085 (-4300 4700);
PAINT GREEN (-4300 4700);
DISPLAY INVISIBLE (-4300 4700);
FORCEPROP 2 LAST CDS_LIB cls
J 0
(-4300 4700);
DISPLAY INVISIBLE (-4300 4700);
FORCEADD VCC..1
(-2450 6150);
FORCEPROP 3 LASTPIN (-2400 6100) SIG_NAME XP1R0V_FPGA\g
J 0
(-2390 6110);
DISPLAY 0.659574 (-2390 6110);
PAINT MONO (-2390 6110);
DISPLAY INVISIBLE (-2390 6110);
FORCEPROP 1 LAST HDL_POWER XP1R0V_FPGA
J 1
(-2390 6190);
DISPLAY 1.021277 (-2390 6190);
PAINT GREEN (-2390 6190);
FORCEPROP 0 LAST VOLTAGE 1.0V
J 0
(-2690 6290);
DISPLAY 1.021277 (-2690 6290);
DISPLAY BOTH (-2690 6290);
FORCEPROP 1 LAST PATH I285
J 0
(-2415 6240);
DISPLAY 0.808511 (-2415 6240);
PAINT GREEN (-2415 6240);
DISPLAY INVISIBLE (-2415 6240);
FORCEPROP 1 LAST BODY_TYPE PLUMBING
J 0
(-2495 6107);
DISPLAY 0.340426 (-2495 6107);
PAINT GREEN (-2495 6107);
DISPLAY INVISIBLE (-2495 6107);
FORCEPROP 2 LAST CDS_LIB cls
J 0
(-2450 6150);
DISPLAY INVISIBLE (-2450 6150);
FORCEPROP 1 LAST CDS_LMAN_SYM_OUTLINE -250,250,250,-250
J 0
(-2450 6150);
DISPLAY 0.468085 (-2450 6150);
PAINT GREEN (-2450 6150);
DISPLAY INVISIBLE (-2450 6150);
FORCEADD VCC..1
(-6450 950);
FORCEPROP 3 LASTPIN (-6400 900) SIG_NAME XP1R0V_FPGA\g
J 0
(-6390 910);
DISPLAY 0.659574 (-6390 910);
PAINT MONO (-6390 910);
DISPLAY INVISIBLE (-6390 910);
FORCEPROP 0 LAST VOLTAGE 1.0V
J 0
(-6690 1090);
DISPLAY 1.021277 (-6690 1090);
DISPLAY BOTH (-6690 1090);
FORCEPROP 1 LAST HDL_POWER XP1R0V_FPGA
J 1
(-6390 990);
DISPLAY 1.021277 (-6390 990);
PAINT GREEN (-6390 990);
FORCEPROP 1 LAST CDS_LMAN_SYM_OUTLINE -250,250,250,-250
J 0
(-6450 950);
DISPLAY 0.468085 (-6450 950);
PAINT GREEN (-6450 950);
DISPLAY INVISIBLE (-6450 950);
FORCEPROP 2 LAST CDS_LIB cls
J 0
(-6450 950);
DISPLAY INVISIBLE (-6450 950);
FORCEPROP 1 LAST BODY_TYPE PLUMBING
J 0
(-6495 907);
DISPLAY 0.340426 (-6495 907);
PAINT GREEN (-6495 907);
DISPLAY INVISIBLE (-6495 907);
FORCEPROP 1 LAST PATH I286
J 0
(-6415 1040);
DISPLAY 0.808511 (-6415 1040);
PAINT GREEN (-6415 1040);
DISPLAY INVISIBLE (-6415 1040);
FORCEADD VCC..1
(-7150 -200);
FORCEPROP 3 LASTPIN (-7100 -250) SIG_NAME XP1R2V_FPGA\g
J 0
(-7090 -240);
DISPLAY 0.659574 (-7090 -240);
PAINT MONO (-7090 -240);
DISPLAY INVISIBLE (-7090 -240);
FORCEPROP 0 LAST VOLTAGE 1.2V
J 0
(-7350 -50);
DISPLAY 1.021277 (-7350 -50);
DISPLAY BOTH (-7350 -50);
FORCEPROP 1 LAST HDL_POWER XP1R2V_FPGA
J 1
(-7095 -145);
DISPLAY 1.021277 (-7095 -145);
PAINT GREEN (-7095 -145);
FORCEPROP 1 LAST CDS_LMAN_SYM_OUTLINE -250,250,250,-250
J 0
(-7150 -200);
DISPLAY 0.468085 (-7150 -200);
PAINT GREEN (-7150 -200);
DISPLAY INVISIBLE (-7150 -200);
FORCEPROP 2 LAST CDS_LIB cls
J 0
(-7150 -200);
DISPLAY INVISIBLE (-7150 -200);
FORCEPROP 1 LAST BODY_TYPE PLUMBING
J 0
(-7195 -243);
DISPLAY 0.340426 (-7195 -243);
PAINT GREEN (-7195 -243);
DISPLAY INVISIBLE (-7195 -243);
FORCEPROP 1 LAST PATH I287
J 0
(-7115 -110);
DISPLAY 0.808511 (-7115 -110);
PAINT GREEN (-7115 -110);
DISPLAY INVISIBLE (-7115 -110);
FORCEADD VCC..1
(-6050 7600);
FORCEPROP 3 LASTPIN (-6000 7550) SIG_NAME XP1R8V_FPGA\g
J 0
(-5990 7560);
DISPLAY 0.659574 (-5990 7560);
PAINT MONO (-5990 7560);
DISPLAY INVISIBLE (-5990 7560);
FORCEPROP 1 LAST HDL_POWER XP1R8V_FPGA
J 1
(-5995 7655);
DISPLAY 1.021277 (-5995 7655);
PAINT GREEN (-5995 7655);
FORCEPROP 0 LAST VOLTAGE 1.8V
J 0
(-6250 7750);
DISPLAY 1.021277 (-6250 7750);
DISPLAY BOTH (-6250 7750);
FORCEPROP 1 LAST PATH I288
J 0
(-6015 7690);
DISPLAY 0.808511 (-6015 7690);
PAINT GREEN (-6015 7690);
DISPLAY INVISIBLE (-6015 7690);
FORCEPROP 1 LAST BODY_TYPE PLUMBING
J 0
(-6095 7557);
DISPLAY 0.340426 (-6095 7557);
PAINT GREEN (-6095 7557);
DISPLAY INVISIBLE (-6095 7557);
FORCEPROP 2 LAST CDS_LIB cls
J 0
(-6050 7600);
DISPLAY INVISIBLE (-6050 7600);
FORCEPROP 1 LAST CDS_LMAN_SYM_OUTLINE -250,250,250,-250
J 0
(-6050 7600);
DISPLAY 0.468085 (-6050 7600);
PAINT GREEN (-6050 7600);
DISPLAY INVISIBLE (-6050 7600);
FORCEADD VCC..1
(-4300 2600);
FORCEPROP 3 LASTPIN (-4250 2550) SIG_NAME XP2R5V_FPGA\g
J 0
(-4240 2560);
DISPLAY 0.659574 (-4240 2560);
PAINT MONO (-4240 2560);
DISPLAY INVISIBLE (-4240 2560);
FORCEPROP 1 LAST HDL_POWER XP2R5V_FPGA
J 1
(-4245 2655);
DISPLAY 1.021277 (-4245 2655);
PAINT GREEN (-4245 2655);
FORCEPROP 0 LAST VOLTAGE 2.5V
J 0
(-4400 2750);
DISPLAY 1.021277 (-4400 2750);
DISPLAY BOTH (-4400 2750);
FORCEPROP 1 LAST PATH I289
J 0
(-4265 2690);
DISPLAY 0.808511 (-4265 2690);
PAINT GREEN (-4265 2690);
DISPLAY INVISIBLE (-4265 2690);
FORCEPROP 1 LAST BODY_TYPE PLUMBING
J 0
(-4345 2557);
DISPLAY 0.340426 (-4345 2557);
PAINT GREEN (-4345 2557);
DISPLAY INVISIBLE (-4345 2557);
FORCEPROP 1 LAST CDS_LMAN_SYM_OUTLINE -250,250,250,-250
J 0
(-4300 2600);
DISPLAY 0.468085 (-4300 2600);
PAINT GREEN (-4300 2600);
DISPLAY INVISIBLE (-4300 2600);
FORCEPROP 2 LAST CDS_LIB cls
J 0
(-4300 2600);
DISPLAY INVISIBLE (-4300 2600);
FORCEADD CAPACITOR..2
(-4950 2050);
FORCEPROP 0 LAST PACKAGE 0805
J 0
(-4900 2300);
DISPLAY 1.021277 (-4900 2300);
FORCEPROP 0 LAST VOLTAGE 10V
J 0
(-4900 2200);
DISPLAY 1.021277 (-4900 2200);
FORCEPROP 1 LAST VALUE 22UF
J 0
(-4900 2100);
DISPLAY 1.212766 (-4900 2100);
PAINT GREEN (-4900 2100);
FORCEPROP 1 LAST PATH I290
J 0
(-5050 2100);
DISPLAY 1.212766 (-5050 2100);
PAINT GREEN (-5050 2100);
DISPLAY INVISIBLE (-5050 2100);
FORCEPROP 1 LAST CLS_PN G107-0F226-CM
J 0
(-5050 2100);
DISPLAY 1.212766 (-5050 2100);
PAINT GREEN (-5050 2100);
DISPLAY INVISIBLE (-5050 2100);
FORCEPROP 1 LAST TOLERANCE 20%
J 0
(-5100 2150);
DISPLAY 1.212766 (-5100 2150);
PAINT GREEN (-5100 2150);
DISPLAY INVISIBLE (-5100 2150);
FORCEPROP 1 LAST CDS_LMAN_SYM_OUTLINE -50,0,50,-50
J 0
(-4950 2050);
DISPLAY 0.468085 (-4950 2050);
PAINT GREEN (-4950 2050);
DISPLAY INVISIBLE (-4950 2050);
FORCEPROP 2 LAST CDS_LIB passive
J 0
(-4950 2050);
DISPLAY INVISIBLE (-4950 2050);
FORCEPROP 1 LAST $LOCATION C291
J 0
(-4900 1900);
DISPLAY 1.212766 (-4900 1900);
PAINT GREEN (-4900 1900);
FORCEPROP 0 LASTPIN (-4950 2150) $PN 1
R 1
J 0
(-4960 2160);
DISPLAY 0.680851 (-4960 2160);
PAINT MONO (-4960 2160);
FORCEPROP 0 LASTPIN (-4950 1900) $PN 2
R 1
J 2
(-4960 1890);
DISPLAY 0.680851 (-4960 1890);
PAINT MONO (-4960 1890);
FORCEPROP 0 LAST CDS_LOCATION C291
J 0
(-4900 2350);
DISPLAY 1.021277 (-4900 2350);
DISPLAY INVISIBLE (-4900 2350);
FORCEPROP 0 LAST $SEC 1
J 0
(-4900 2350);
DISPLAY 0.680851 (-4900 2350);
PAINT MONO (-4900 2350);
DISPLAY INVISIBLE (-4900 2350);
FORCEPROP 0 LAST CDS_SEC 1
J 0
(-4900 2350);
DISPLAY 1.021277 (-4900 2350);
DISPLAY INVISIBLE (-4900 2350);
FORCEADD CAPACITOR..2
(-4600 2050);
FORCEPROP 0 LAST PACKAGE 0805
J 0
(-4550 2300);
DISPLAY 1.021277 (-4550 2300);
FORCEPROP 0 LAST VOLTAGE 10V
J 0
(-4550 2200);
DISPLAY 1.021277 (-4550 2200);
FORCEPROP 1 LAST VALUE 22UF
J 0
(-4550 2100);
DISPLAY 1.212766 (-4550 2100);
PAINT GREEN (-4550 2100);
FORCEPROP 1 LAST PATH I291
J 0
(-4700 2100);
DISPLAY 1.212766 (-4700 2100);
PAINT GREEN (-4700 2100);
DISPLAY INVISIBLE (-4700 2100);
FORCEPROP 1 LAST CLS_PN G107-0F226-CM
J 0
(-4700 2100);
DISPLAY 1.212766 (-4700 2100);
PAINT GREEN (-4700 2100);
DISPLAY INVISIBLE (-4700 2100);
FORCEPROP 1 LAST TOLERANCE 20%
J 0
(-4750 2150);
DISPLAY 1.212766 (-4750 2150);
PAINT GREEN (-4750 2150);
DISPLAY INVISIBLE (-4750 2150);
FORCEPROP 1 LAST CDS_LMAN_SYM_OUTLINE -50,0,50,-50
J 0
(-4600 2050);
DISPLAY 0.468085 (-4600 2050);
PAINT GREEN (-4600 2050);
DISPLAY INVISIBLE (-4600 2050);
FORCEPROP 2 LAST CDS_LIB passive
J 0
(-4600 2050);
DISPLAY INVISIBLE (-4600 2050);
FORCEPROP 1 LAST $LOCATION C292
J 0
(-4550 1900);
DISPLAY 1.212766 (-4550 1900);
PAINT GREEN (-4550 1900);
FORCEPROP 0 LASTPIN (-4600 2150) $PN 1
R 1
J 0
(-4610 2160);
DISPLAY 0.680851 (-4610 2160);
PAINT MONO (-4610 2160);
FORCEPROP 0 LASTPIN (-4600 1900) $PN 2
R 1
J 2
(-4610 1890);
DISPLAY 0.680851 (-4610 1890);
PAINT MONO (-4610 1890);
FORCEPROP 0 LAST CDS_LOCATION C292
J 0
(-4550 2350);
DISPLAY 1.021277 (-4550 2350);
DISPLAY INVISIBLE (-4550 2350);
FORCEPROP 0 LAST $SEC 1
J 0
(-4550 2350);
DISPLAY 0.680851 (-4550 2350);
PAINT MONO (-4550 2350);
DISPLAY INVISIBLE (-4550 2350);
FORCEPROP 0 LAST CDS_SEC 1
J 0
(-4550 2350);
DISPLAY 1.021277 (-4550 2350);
DISPLAY INVISIBLE (-4550 2350);
FORCEADD CAPACITOR..2
(-6050 2050);
FORCEPROP 1 LAST VALUE 4.7UF
J 0
(-6000 2100);
DISPLAY 1.212766 (-6000 2100);
PAINT GREEN (-6000 2100);
FORCEPROP 0 LAST PACKAGE 0402
J 0
(-6000 2300);
DISPLAY 1.021277 (-6000 2300);
FORCEPROP 0 LAST VOLTAGE 6.3V
J 0
(-6000 2200);
DISPLAY 1.021277 (-6000 2200);
FORCEPROP 1 LAST PATH I292
J 0
(-6150 2100);
DISPLAY 1.212766 (-6150 2100);
PAINT GREEN (-6150 2100);
DISPLAY INVISIBLE (-6150 2100);
FORCEPROP 2 LAST CDS_LIB passive
J 0
(-6050 2050);
DISPLAY INVISIBLE (-6050 2050);
FORCEPROP 1 LAST CDS_LMAN_SYM_OUTLINE -50,0,50,-50
J 0
(-6050 2050);
DISPLAY 0.468085 (-6050 2050);
PAINT GREEN (-6050 2050);
DISPLAY INVISIBLE (-6050 2050);
FORCEPROP 1 LAST CLS_PN G105-0F475-BM
J 0
(-6150 2100);
DISPLAY 1.212766 (-6150 2100);
PAINT GREEN (-6150 2100);
DISPLAY INVISIBLE (-6150 2100);
FORCEPROP 1 LAST TOLERANCE 20%
J 0
(-6200 2150);
DISPLAY 1.212766 (-6200 2150);
PAINT GREEN (-6200 2150);
DISPLAY INVISIBLE (-6200 2150);
FORCEPROP 1 LAST $LOCATION C93
J 0
(-6000 1900);
DISPLAY 1.212766 (-6000 1900);
PAINT GREEN (-6000 1900);
FORCEPROP 0 LASTPIN (-6050 2150) $PN 1
R 1
J 0
(-6060 2160);
DISPLAY 0.680851 (-6060 2160);
PAINT MONO (-6060 2160);
FORCEPROP 0 LASTPIN (-6050 1900) $PN 2
R 1
J 2
(-6060 1890);
DISPLAY 0.680851 (-6060 1890);
PAINT MONO (-6060 1890);
FORCEPROP 0 LAST CDS_LOCATION C93
J 0
(-6000 2350);
DISPLAY 1.021277 (-6000 2350);
DISPLAY INVISIBLE (-6000 2350);
FORCEPROP 0 LAST $SEC 1
J 0
(-6000 2350);
DISPLAY 0.680851 (-6000 2350);
PAINT MONO (-6000 2350);
DISPLAY INVISIBLE (-6000 2350);
FORCEPROP 0 LAST CDS_SEC 1
J 0
(-6000 2350);
DISPLAY 1.021277 (-6000 2350);
DISPLAY INVISIBLE (-6000 2350);
FORCEADD GND_SG..1
(-11000 1700);
FORCEPROP 3 LASTPIN (-10950 1750) SIG_NAME SG\g
J 0
(-10940 1760);
DISPLAY 0.659574 (-10940 1760);
PAINT MONO (-10940 1760);
DISPLAY INVISIBLE (-10940 1760);
FORCEPROP 1 LAST HDL_POWER SG
J 1
(-10945 1605);
DISPLAY 0.808511 (-10945 1605);
PAINT GREEN (-10945 1605);
FORCEPROP 1 LAST PATH I293
J 0
(-10965 1700);
DISPLAY 0.808511 (-10965 1700);
PAINT GREEN (-10965 1700);
DISPLAY INVISIBLE (-10965 1700);
FORCEPROP 1 LAST BODY_TYPE PLUMBING
J 0
(-10985 1685);
DISPLAY 0.808511 (-10985 1685);
PAINT GREEN (-10985 1685);
DISPLAY INVISIBLE (-10985 1685);
FORCEPROP 1 LAST CDS_LMAN_SYM_OUTLINE 0,0,100,-50
J 0
(-11000 1700);
DISPLAY 0.468085 (-11000 1700);
PAINT GREEN (-11000 1700);
DISPLAY INVISIBLE (-11000 1700);
FORCEPROP 2 LAST CDS_LIB cls
J 0
(-11000 1700);
DISPLAY INVISIBLE (-11000 1700);
FORCEADD FERRITEBEAD..1
(-8400 -350);
FORCEPROP 1 LAST VALUE 120OHM
J 0
(-8050 -300);
DISPLAY 1.212766 (-8050 -300);
PAINT GREEN (-8050 -300);
FORCEPROP 0 LAST PACKAGE 0603
J 0
(-8400 -300);
DISPLAY 1.021277 (-8400 -300);
FORCEPROP 1 LAST TOLERANCE 25%
J 0
(-8500 -300);
DISPLAY 1.212766 (-8500 -300);
PAINT GREEN (-8500 -300);
DISPLAY INVISIBLE (-8500 -300);
FORCEPROP 1 LAST PATH I36
J 2
(-8450 -300);
DISPLAY 1.212766 (-8450 -300);
PAINT GREEN (-8450 -300);
DISPLAY INVISIBLE (-8450 -300);
FORCEPROP 1 LAST CLS_PN G191-10100-01
J 2
(-8450 -300);
DISPLAY 1.212766 (-8450 -300);
PAINT GREEN (-8450 -300);
DISPLAY INVISIBLE (-8450 -300);
FORCEPROP 1 LAST CDS_LMAN_SYM_OUTLINE 0,0,200,-100
J 0
(-8400 -350);
DISPLAY 0.468085 (-8400 -350);
PAINT GREEN (-8400 -350);
DISPLAY INVISIBLE (-8400 -350);
FORCEPROP 2 LAST CDS_LIB passive
J 0
(-8400 -350);
DISPLAY INVISIBLE (-8400 -350);
FORCEPROP 1 LAST $LOCATION L35
J 2
(-8500 -300);
DISPLAY 1.212766 (-8500 -300);
PAINT GREEN (-8500 -300);
FORCEPROP 0 LASTPIN (-8500 -400) $PN 1
J 2
(-8510 -390);
DISPLAY 0.680851 (-8510 -390);
PAINT MONO (-8510 -390);
FORCEPROP 0 LASTPIN (-8100 -400) $PN 2
J 0
(-8090 -390);
DISPLAY 0.680851 (-8090 -390);
PAINT MONO (-8090 -390);
FORCEPROP 0 LAST CDS_LOCATION L35
J 2
(-8510 -391);
DISPLAY 1.212766 (-8510 -391);
PAINT GREEN (-8510 -391);
DISPLAY INVISIBLE (-8510 -391);
FORCEPROP 0 LAST $SEC 1
J 0
(-8000 -300);
DISPLAY 0.680851 (-8000 -300);
PAINT MONO (-8000 -300);
DISPLAY INVISIBLE (-8000 -300);
FORCEPROP 0 LAST CDS_SEC 1
J 0
(-8000 -300);
DISPLAY 1.021277 (-8000 -300);
DISPLAY INVISIBLE (-8000 -300);
FORCEADD FERRITEBEAD..1
(-7650 750);
FORCEPROP 1 LAST VALUE 120OHM
J 0
(-7400 750);
DISPLAY 1.212766 (-7400 750);
PAINT GREEN (-7400 750);
FORCEPROP 0 LAST PACKAGE 0603
J 0
(-7650 800);
DISPLAY 1.021277 (-7650 800);
FORCEPROP 1 LAST TOLERANCE 25%
J 0
(-7750 800);
DISPLAY 1.212766 (-7750 800);
PAINT GREEN (-7750 800);
DISPLAY INVISIBLE (-7750 800);
FORCEPROP 1 LAST PATH I37
J 2
(-7700 800);
DISPLAY 1.212766 (-7700 800);
PAINT GREEN (-7700 800);
DISPLAY INVISIBLE (-7700 800);
FORCEPROP 1 LAST CLS_PN G191-10100-01
J 2
(-7700 800);
DISPLAY 1.212766 (-7700 800);
PAINT GREEN (-7700 800);
DISPLAY INVISIBLE (-7700 800);
FORCEPROP 2 LAST CDS_LIB passive
J 0
(-7650 750);
DISPLAY INVISIBLE (-7650 750);
FORCEPROP 1 LAST CDS_LMAN_SYM_OUTLINE 0,0,200,-100
J 0
(-7650 750);
DISPLAY 0.468085 (-7650 750);
PAINT GREEN (-7650 750);
DISPLAY INVISIBLE (-7650 750);
FORCEPROP 1 LAST $LOCATION L34
J 2
(-7810 709);
DISPLAY 1.212766 (-7810 709);
PAINT GREEN (-7810 709);
FORCEPROP 0 LASTPIN (-7750 700) $PN 1
J 2
(-7760 710);
DISPLAY 0.680851 (-7760 710);
PAINT MONO (-7760 710);
FORCEPROP 0 LASTPIN (-7350 700) $PN 2
J 0
(-7340 710);
DISPLAY 0.680851 (-7340 710);
PAINT MONO (-7340 710);
FORCEPROP 0 LAST CDS_LOCATION L34
J 2
(-7810 709);
DISPLAY 1.212766 (-7810 709);
PAINT GREEN (-7810 709);
DISPLAY INVISIBLE (-7810 709);
FORCEPROP 0 LAST $SEC 1
J 0
(-7400 850);
DISPLAY 0.680851 (-7400 850);
PAINT MONO (-7400 850);
DISPLAY INVISIBLE (-7400 850);
FORCEPROP 0 LAST CDS_SEC 1
J 0
(-7400 850);
DISPLAY 1.021277 (-7400 850);
DISPLAY INVISIBLE (-7400 850);
FORCEADD GND_SG..1
(-10200 50);
FORCEPROP 3 LASTPIN (-10150 100) SIG_NAME SG\g
J 0
(-10140 110);
DISPLAY 0.659574 (-10140 110);
PAINT MONO (-10140 110);
DISPLAY INVISIBLE (-10140 110);
FORCEPROP 1 LAST HDL_POWER SG
J 1
(-10145 -45);
DISPLAY 0.808511 (-10145 -45);
PAINT GREEN (-10145 -45);
FORCEPROP 1 LAST PATH I5
J 0
(-10165 50);
DISPLAY 0.808511 (-10165 50);
PAINT GREEN (-10165 50);
DISPLAY INVISIBLE (-10165 50);
FORCEPROP 1 LAST BODY_TYPE PLUMBING
J 0
(-10185 35);
DISPLAY 0.808511 (-10185 35);
PAINT GREEN (-10185 35);
DISPLAY INVISIBLE (-10185 35);
FORCEPROP 2 LAST CDS_LIB cls
J 0
(-10200 50);
DISPLAY INVISIBLE (-10200 50);
FORCEPROP 1 LAST CDS_LMAN_SYM_OUTLINE 0,0,100,-50
J 0
(-10200 50);
DISPLAY 0.468085 (-10200 50);
PAINT GREEN (-10200 50);
DISPLAY INVISIBLE (-10200 50);
FORCEADD GND_SG..1
(-11000 3950);
FORCEPROP 3 LASTPIN (-10950 4000) SIG_NAME SG\g
J 0
(-10940 4010);
DISPLAY 0.659574 (-10940 4010);
PAINT MONO (-10940 4010);
DISPLAY INVISIBLE (-10940 4010);
FORCEPROP 1 LAST HDL_POWER SG
J 1
(-10945 3855);
DISPLAY 0.808511 (-10945 3855);
PAINT GREEN (-10945 3855);
FORCEPROP 1 LAST PATH I59
J 0
(-10965 3950);
DISPLAY 0.808511 (-10965 3950);
PAINT GREEN (-10965 3950);
DISPLAY INVISIBLE (-10965 3950);
FORCEPROP 1 LAST BODY_TYPE PLUMBING
J 0
(-10985 3935);
DISPLAY 0.808511 (-10985 3935);
PAINT GREEN (-10985 3935);
DISPLAY INVISIBLE (-10985 3935);
FORCEPROP 1 LAST CDS_LMAN_SYM_OUTLINE 0,0,100,-50
J 0
(-11000 3950);
DISPLAY 0.468085 (-11000 3950);
PAINT GREEN (-11000 3950);
DISPLAY INVISIBLE (-11000 3950);
FORCEPROP 2 LAST CDS_LIB cls
J 0
(-11000 3950);
DISPLAY INVISIBLE (-11000 3950);
FORCEADD GND_SG..1
(-11000 6800);
FORCEPROP 3 LASTPIN (-10950 6850) SIG_NAME SG\g
J 0
(-10940 6860);
DISPLAY 0.659574 (-10940 6860);
PAINT MONO (-10940 6860);
DISPLAY INVISIBLE (-10940 6860);
FORCEPROP 1 LAST HDL_POWER SG
J 1
(-10945 6705);
DISPLAY 0.808511 (-10945 6705);
PAINT GREEN (-10945 6705);
FORCEPROP 1 LAST PATH I64
J 0
(-10965 6800);
DISPLAY 0.808511 (-10965 6800);
PAINT GREEN (-10965 6800);
DISPLAY INVISIBLE (-10965 6800);
FORCEPROP 1 LAST BODY_TYPE PLUMBING
J 0
(-10985 6785);
DISPLAY 0.808511 (-10985 6785);
PAINT GREEN (-10985 6785);
DISPLAY INVISIBLE (-10985 6785);
FORCEPROP 2 LAST CDS_LIB cls
J 0
(-11000 6800);
DISPLAY INVISIBLE (-11000 6800);
FORCEPROP 1 LAST CDS_LMAN_SYM_OUTLINE 0,0,100,-50
J 0
(-11000 6800);
DISPLAY 0.468085 (-11000 6800);
PAINT GREEN (-11000 6800);
DISPLAY INVISIBLE (-11000 6800);
FORCEADD GND_SG..1
(-11000 5300);
FORCEPROP 3 LASTPIN (-10950 5350) SIG_NAME SG\g
J 0
(-10940 5360);
DISPLAY 0.659574 (-10940 5360);
PAINT MONO (-10940 5360);
DISPLAY INVISIBLE (-10940 5360);
FORCEPROP 1 LAST HDL_POWER SG
J 1
(-10945 5205);
DISPLAY 0.808511 (-10945 5205);
PAINT GREEN (-10945 5205);
FORCEPROP 1 LAST PATH I73
J 0
(-10965 5300);
DISPLAY 0.808511 (-10965 5300);
PAINT GREEN (-10965 5300);
DISPLAY INVISIBLE (-10965 5300);
FORCEPROP 1 LAST BODY_TYPE PLUMBING
J 0
(-10985 5285);
DISPLAY 0.808511 (-10985 5285);
PAINT GREEN (-10985 5285);
DISPLAY INVISIBLE (-10985 5285);
FORCEPROP 2 LAST CDS_LIB cls
J 0
(-11000 5300);
DISPLAY INVISIBLE (-11000 5300);
FORCEPROP 1 LAST CDS_LMAN_SYM_OUTLINE 0,0,100,-50
J 0
(-11000 5300);
DISPLAY 0.468085 (-11000 5300);
PAINT GREEN (-11000 5300);
DISPLAY INVISIBLE (-11000 5300);
FORCEADD SHEET_A1..1
(-450 -2100);
FORCEPROP 2 LAST CUSTOM_TXT_CDS <XR_PAGE_TITLE>
J 0
(-16020 9250);
DISPLAY 0.638298 (-16020 9250);
PAINT PINK (-16020 9250);
FORCEPROP 1 LAST CUSTOM_TXT_CDS <DOCNO>
J 0
(-2500 -1715);
DISPLAY 0.978723 (-2500 -1715);
FORCEPROP 1 LAST CUSTOM_TXT_CDS <CON_PAGE_NUM>
J 0
(-2605 -2050);
DISPLAY 0.978723 (-2605 -2050);
FORCEPROP 1 LAST CUSTOM_TXT_CDS <DATE>
J 0
(-1150 -1925);
DISPLAY 0.978723 (-1150 -1925);
FORCEPROP 1 LAST CUSTOM_TXT_CDS <TITLE>
J 1
(-2235 -1470);
DISPLAY 0.978723 (-2235 -1470);
FORCEPROP 1 LAST CUSTOM_TXT_CDS <DESIGNER>
J 0
(-1150 -1500);
DISPLAY 0.978723 (-1150 -1500);
FORCEPROP 1 LAST CUSTOM_TXT_CDS <CON_TOTAL_PAGES>
J 0
(-2295 -2050);
DISPLAY 0.808511 (-2295 -2050);
FORCEPROP 1 LAST CUSTOM_TXT_CDS <ASSY_PN>
J 0
(-2500 -1925);
DISPLAY 0.978723 (-2500 -1925);
FORCEPROP 1 LAST CUSTOM_TXT_CDS <DOCREV>
J 0
(-1150 -1725);
DISPLAY 0.978723 (-1150 -1725);
FORCEPROP 1 LAST TITLE FPGA_5/5
J 0
(-2950 -1200);
DISPLAY 3.042553 (-2950 -1200);
PAINT GREEN (-2950 -1200);
FORCEPROP 1 LAST COMMENT_BODY TRUE
J 0
(-440 -2045);
DISPLAY 0.808511 (-440 -2045);
DISPLAY INVISIBLE (-440 -2045);
FORCEPROP 2 LAST CDS_LIB cls
J 0
(-450 -2100);
DISPLAY INVISIBLE (-450 -2100);
FORCEPROP 1 LAST CDS_LMAN_SYM_OUTLINE -15850,11500,200,-200
J 0
(-450 -2100);
DISPLAY 0.468085 (-450 -2100);
PAINT GREEN (-450 -2100);
DISPLAY INVISIBLE (-450 -2100);
FORCEPROP 2 LAST PAGE_BORDER TRUE
J 0
(-16020 9250);
DISPLAY 0.638298 (-16020 9250);
PAINT PINK (-16020 9250);
DISPLAY INVISIBLE (-16020 9250);
FORCEPROP 2 LAST CDS_XR_PAGE_TITLE CR-14 : @TIMECARD_LIB.TIMECARD(SCH_1):PAGE14
J 0
(-16020 9250);
DISPLAY 0.638298 (-16020 9250);
PAINT PINK (-16020 9250);
DISPLAY INVISIBLE (-16020 9250);
WIRE 16 -1 (-10950 -950)(-10950 -1000);
WIRE 16 -1 (-10950 -950)(-10600 -950);
WIRE 16 -1 (-10950 -950)(-10950 -800);
WIRE 16 -1 (-10950 3150)(-10950 3200);
WIRE 16 -1 (-11200 -250)(-11200 -400);
WIRE 16 -1 (-14450 -800)(-14450 -900);
WIRE 16 -1 (-14450 -800)(-14150 -800);
WIRE 16 -1 (-14450 -600)(-14450 -800);
WIRE 16 -1 (-4250 4650)(-4250 4550);
WIRE 16 -1 (-2400 5950)(-2400 6100);
WIRE 16 -1 (-2950 5950)(-2400 5950);
WIRE 16 -1 (-2400 5800)(-2400 5950);
WIRE 16 -1 (-6400 700)(-6400 900);
WIRE 16 -1 (-6400 700)(-6750 700);
WIRE 16 -1 (-7100 -400)(-7100 -250);
WIRE 16 -1 (-7100 -400)(-7550 -400);
WIRE 16 -1 (-6000 7400)(-6000 7550);
WIRE 16 -1 (-6000 7400)(-6400 7400);
WIRE 16 -1 (-4250 2550)(-4250 2300);
WIRE 16 -1 (-10950 1750)(-10950 1800);
WIRE 16 -1 (-10150 100)(-10150 150);
WIRE 16 -1 (-10950 4000)(-10950 4050);
WIRE 16 -1 (-10950 6850)(-10950 6900);
WIRE 16 -1 (-10950 5350)(-10950 5450);
WIRE 16 -1 (-2400 5550)(-2400 5450);
WIRE 16 -1 (-2950 5550)(-2950 5450);
WIRE 16 -1 (-2400 5450)(-2950 5450);
WIRE 16 -1 (-3600 5550)(-3600 5450);
WIRE 16 -1 (-2950 5450)(-3600 5450);
WIRE 16 -1 (-3950 5550)(-3950 5450);
WIRE 16 -1 (-3950 5450)(-3600 5450);
WIRE 16 -1 (-4300 5550)(-4300 5450);
WIRE 16 -1 (-4300 5450)(-3950 5450);
WIRE 16 -1 (-4650 5450)(-4650 5550);
WIRE 16 -1 (-4300 5450)(-4650 5450);
WIRE 16 -1 (-5000 5550)(-5000 5450);
WIRE 16 -1 (-4650 5450)(-5000 5450);
WIRE 16 -1 (-5400 5550)(-5400 5450);
WIRE 16 -1 (-5000 5450)(-5400 5450);
WIRE 16 -1 (-5750 5550)(-5750 5450);
WIRE 16 -1 (-5750 5450)(-5400 5450);
WIRE 16 -1 (-6150 5550)(-6150 5450);
WIRE 16 -1 (-6150 5450)(-5750 5450);
WIRE 16 -1 (-6500 5550)(-6500 5450);
WIRE 16 -1 (-6150 5450)(-6500 5450);
WIRE 16 -1 (-6850 5450)(-6850 5550);
WIRE 16 -1 (-6500 5450)(-6850 5450);
WIRE 16 -1 (-7200 5550)(-7200 5450);
WIRE 16 -1 (-7200 5450)(-6850 5450);
WIRE 16 -1 (-7600 5550)(-7600 5450);
WIRE 16 -1 (-7600 5450)(-7200 5450);
WIRE 16 -1 (-8000 5550)(-8000 5450);
WIRE 16 -1 (-8000 5450)(-7600 5450);
WIRE 16 -1 (-8350 5550)(-8350 5450);
WIRE 16 -1 (-8350 5450)(-8000 5450);
WIRE 16 -1 (-8750 5550)(-8750 5450);
WIRE 16 -1 (-8750 5450)(-8350 5450);
WIRE 16 -1 (-9100 5550)(-9100 5450);
WIRE 16 -1 (-9100 5450)(-8750 5450);
WIRE 16 -1 (-9450 5550)(-9450 5450);
WIRE 16 -1 (-9450 5450)(-9100 5450);
WIRE 16 -1 (-9800 5550)(-9800 5450);
WIRE 16 -1 (-9800 5450)(-9450 5450);
WIRE 16 -1 (-10200 5550)(-10200 5450);
WIRE 16 -1 (-10200 5450)(-9800 5450);
WIRE 16 -1 (-10600 5550)(-10600 5450);
WIRE 16 -1 (-10600 5450)(-10200 5450);
WIRE 16 -1 (-10950 5450)(-10950 5550);
WIRE 16 -1 (-10950 5450)(-10600 5450);
WIRE 16 -1 (-6400 7000)(-6400 6900);
WIRE 16 -1 (-6900 7000)(-6900 6900);
WIRE 16 -1 (-6400 6900)(-6900 6900);
WIRE 16 -1 (-7900 7000)(-7900 6900);
WIRE 16 -1 (-6900 6900)(-7900 6900);
WIRE 16 -1 (-8350 7000)(-8350 6900);
WIRE 16 -1 (-8350 6900)(-7900 6900);
WIRE 16 -1 (-8750 7000)(-8750 6900);
WIRE 16 -1 (-8350 6900)(-8750 6900);
WIRE 16 -1 (-9100 7000)(-9100 6900);
WIRE 16 -1 (-9100 6900)(-8750 6900);
WIRE 16 -1 (-9500 7000)(-9500 6900);
WIRE 16 -1 (-9500 6900)(-9100 6900);
WIRE 16 -1 (-9900 7000)(-9900 6900);
WIRE 16 -1 (-9900 6900)(-9500 6900);
WIRE 16 -1 (-10250 7000)(-10250 6900);
WIRE 16 -1 (-10250 6900)(-9900 6900);
WIRE 16 -1 (-10600 7000)(-10600 6900);
WIRE 16 -1 (-10600 6900)(-10250 6900);
WIRE 16 -1 (-10950 6900)(-10600 6900);
WIRE 16 -1 (-10950 7000)(-10950 6900);
WIRE 16 -1 (-4600 4150)(-4600 4050);
WIRE 16 -1 (-5000 4050)(-4600 4050);
WIRE 16 -1 (-5000 4050)(-5000 4150);
WIRE 16 -1 (-5350 4050)(-5000 4050);
WIRE 16 -1 (-5350 4150)(-5350 4050);
WIRE 16 -1 (-5700 4050)(-5350 4050);
WIRE 16 -1 (-5700 4150)(-5700 4050);
WIRE 16 -1 (-6050 4050)(-5700 4050);
WIRE 16 -1 (-6050 4150)(-6050 4050);
WIRE 16 -1 (-6400 4050)(-6050 4050);
WIRE 16 -1 (-6400 4150)(-6400 4050);
WIRE 16 -1 (-6750 4050)(-6400 4050);
WIRE 16 -1 (-6750 4150)(-6750 4050);
WIRE 16 -1 (-7150 4050)(-6750 4050);
WIRE 16 -1 (-7150 4150)(-7150 4050);
WIRE 16 -1 (-7500 4050)(-7150 4050);
WIRE 16 -1 (-7500 4150)(-7500 4050);
WIRE 16 -1 (-7900 4050)(-7500 4050);
WIRE 16 -1 (-7900 4150)(-7900 4050);
WIRE 16 -1 (-8250 4150)(-8250 4050);
WIRE 16 -1 (-7900 4050)(-8250 4050);
WIRE 16 -1 (-8250 4050)(-8600 4050);
WIRE 16 -1 (-8600 4050)(-8600 4150);
WIRE 16 -1 (-8950 4050)(-8600 4050);
WIRE 16 -1 (-8950 4150)(-8950 4050);
WIRE 16 -1 (-9350 4050)(-8950 4050);
WIRE 16 -1 (-9350 4150)(-9350 4050);
WIRE 16 -1 (-9800 4050)(-9350 4050);
WIRE 16 -1 (-9800 4150)(-9800 4050);
WIRE 16 -1 (-10200 4050)(-9800 4050);
WIRE 16 -1 (-10200 4150)(-10200 4050);
WIRE 16 -1 (-10550 4050)(-10200 4050);
WIRE 16 -1 (-10550 4150)(-10550 4050);
WIRE 16 -1 (-10950 4050)(-10550 4050);
WIRE 16 -1 (-10950 4150)(-10950 4050);
WIRE 16 -1 (-6750 300)(-6750 150);
WIRE 16 -1 (-7200 300)(-7200 150);
WIRE 16 -1 (-7200 150)(-6750 150);
WIRE 16 -1 (-7950 300)(-7950 150);
WIRE 16 -1 (-7950 150)(-7200 150);
WIRE 16 -1 (-8350 300)(-8350 150);
WIRE 16 -1 (-8350 150)(-7950 150);
WIRE 16 -1 (-8700 300)(-8700 150);
WIRE 16 -1 (-8700 150)(-8350 150);
WIRE 16 -1 (-9050 300)(-9050 150);
WIRE 16 -1 (-9050 150)(-8700 150);
WIRE 16 -1 (-9400 300)(-9400 150);
WIRE 16 -1 (-9400 150)(-9050 150);
WIRE 16 -1 (-9750 300)(-9750 150);
WIRE 16 -1 (-9750 150)(-9400 150);
WIRE 16 -1 (-10150 150)(-10150 300);
WIRE 16 -1 (-10150 150)(-9750 150);
WIRE 16 -1 (-4600 1900)(-4600 1800);
WIRE 16 -1 (-4950 1900)(-4950 1800);
WIRE 16 -1 (-4600 1800)(-4950 1800);
WIRE 16 -1 (-5350 1900)(-5350 1800);
WIRE 16 -1 (-4950 1800)(-5350 1800);
WIRE 16 -1 (-5700 1800)(-5700 1900);
WIRE 16 -1 (-5700 1800)(-5350 1800);
WIRE 16 -1 (-6050 1900)(-6050 1800);
WIRE 16 -1 (-5700 1800)(-6050 1800);
WIRE 16 -1 (-6450 1900)(-6450 1800);
WIRE 16 -1 (-6050 1800)(-6450 1800);
WIRE 16 -1 (-6900 1900)(-6900 1800);
WIRE 16 -1 (-6450 1800)(-6900 1800);
WIRE 16 -1 (-7250 1900)(-7250 1800);
WIRE 16 -1 (-7250 1800)(-6900 1800);
WIRE 16 -1 (-7600 1900)(-7600 1800);
WIRE 16 -1 (-7600 1800)(-7250 1800);
WIRE 16 -1 (-8000 1900)(-8000 1800);
WIRE 16 -1 (-8000 1800)(-7600 1800);
WIRE 16 -1 (-8400 1900)(-8400 1800);
WIRE 16 -1 (-8400 1800)(-8000 1800);
WIRE 16 -1 (-8750 1800)(-8750 1900);
WIRE 16 -1 (-8400 1800)(-8750 1800);
WIRE 16 -1 (-9100 1900)(-9100 1800);
WIRE 16 -1 (-9100 1800)(-8750 1800);
WIRE 16 -1 (-9500 1900)(-9500 1800);
WIRE 16 -1 (-9500 1800)(-9100 1800);
WIRE 16 -1 (-9900 1900)(-9900 1800);
WIRE 16 -1 (-9900 1800)(-9500 1800);
WIRE 16 -1 (-10250 1900)(-10250 1800);
WIRE 16 -1 (-10250 1800)(-9900 1800);
WIRE 16 -1 (-10600 1900)(-10600 1800);
WIRE 16 -1 (-10250 1800)(-10600 1800);
WIRE 16 -1 (-10600 1800)(-10950 1800);
WIRE 16 -1 (-10950 1900)(-10950 1800);
WIRE 16 -1 (-12550 1100)(-12850 1100);
WIRE 16 -1 (-12850 1200)(-12550 1200);
WIRE 16 -1 (-12550 1200)(-12550 1100);
WIRE 16 -1 (-12850 1300)(-12550 1300);
WIRE 16 -1 (-12550 1300)(-12550 1200);
WIRE 16 -1 (-12850 1400)(-12550 1400);
WIRE 16 -1 (-12550 1400)(-12550 1300);
WIRE 16 -1 (-12850 1500)(-12550 1500);
WIRE 16 -1 (-12550 1500)(-12550 1400);
WIRE 16 -1 (-12850 1600)(-12550 1600);
WIRE 16 -1 (-12550 1600)(-12550 1500);
WIRE 16 -1 (-12550 1800)(-12850 1800);
WIRE 16 -1 (-12550 1600)(-12550 1800);
WIRE 16 -1 (-12850 1900)(-12550 1900);
WIRE 16 -1 (-12550 1900)(-12550 1800);
WIRE 16 -1 (-12850 2000)(-12550 2000);
WIRE 16 -1 (-12550 2000)(-12550 1900);
WIRE 16 -1 (-12550 2100)(-12550 2000);
WIRE 16 -1 (-12850 2100)(-12550 2100);
WIRE 16 -1 (-12850 2200)(-12550 2200);
WIRE 16 -1 (-12550 2200)(-12550 2100);
WIRE 16 -1 (-12850 2300)(-12550 2300);
WIRE 16 -1 (-12550 2200)(-12550 2300);
WIRE 16 -1 (-12550 2300)(-10950 2300);
WIRE 16 -1 (-10950 2150)(-10950 2300);
WIRE 16 -1 (-10950 2300)(-10600 2300);
WIRE 16 -1 (-10600 2150)(-10600 2300);
WIRE 16 -1 (-10600 2300)(-10250 2300);
WIRE 16 -1 (-10250 2150)(-10250 2300);
WIRE 16 -1 (-10250 2300)(-9900 2300);
WIRE 16 -1 (-9900 2150)(-9900 2300);
WIRE 16 -1 (-9900 2300)(-9500 2300);
WIRE 16 -1 (-9500 2150)(-9500 2300);
WIRE 16 -1 (-9500 2300)(-9100 2300);
WIRE 16 -1 (-9100 2150)(-9100 2300);
WIRE 16 -1 (-9100 2300)(-8750 2300);
WIRE 16 -1 (-8750 2150)(-8750 2300);
WIRE 16 -1 (-8750 2300)(-8400 2300);
WIRE 16 -1 (-8400 2150)(-8400 2300);
WIRE 16 -1 (-8400 2300)(-8000 2300);
WIRE 16 -1 (-8000 2150)(-8000 2300);
WIRE 16 -1 (-8000 2300)(-7600 2300);
WIRE 16 -1 (-7600 2300)(-7600 2150);
WIRE 16 -1 (-7600 2300)(-7250 2300);
WIRE 16 -1 (-7250 2300)(-7250 2150);
WIRE 16 -1 (-7250 2300)(-6900 2300);
WIRE 16 -1 (-6900 2300)(-6900 2150);
WIRE 16 -1 (-6900 2300)(-6450 2300);
WIRE 16 -1 (-6450 2150)(-6450 2300);
WIRE 16 -1 (-6050 2300)(-6450 2300);
WIRE 16 -1 (-6050 2150)(-6050 2300);
WIRE 16 -1 (-5700 2300)(-6050 2300);
WIRE 16 -1 (-5700 2150)(-5700 2300);
WIRE 16 -1 (-5700 2300)(-5350 2300);
WIRE 16 -1 (-5350 2150)(-5350 2300);
WIRE 16 -1 (-5350 2300)(-4950 2300);
WIRE 16 -1 (-4950 2300)(-4950 2150);
WIRE 16 -1 (-4950 2300)(-4600 2300);
WIRE 16 -1 (-4600 2300)(-4600 2150);
WIRE 16 -1 (-4600 2300)(-4250 2300);
WIRE 16 -1 (-6400 7250)(-6400 7400);
WIRE 16 -1 (-7200 7400)(-6900 7400);
WIRE 16 -1 (-6900 7400)(-6900 7250);
WIRE 16 -1 (-6900 7400)(-6400 7400);
WIRE 16 -1 (-7550 -550)(-7550 -400);
WIRE 16 -1 (-8000 -400)(-8000 -550);
WIRE 16 -1 (-8100 -400)(-8000 -400);
WIRE 16 -1 (-8000 -400)(-7550 -400);
WIRE 16 -1 (-7200 700)(-7200 550);
WIRE 16 -1 (-7350 700)(-7200 700);
WIRE 16 -1 (-7200 700)(-6750 700);
WIRE 16 -1 (-6750 700)(-6750 550);
WIRE 16 -1 (-2950 5950)(-2950 5800);
WIRE 16 -1 (-2950 5950)(-3050 5950);
WIRE 16 -1 (-12550 2500)(-12850 2500);
WIRE 16 -1 (-12850 2600)(-12550 2600);
WIRE 16 -1 (-12550 2600)(-12550 2500);
WIRE 16 -1 (-12850 2700)(-12550 2700);
WIRE 16 -1 (-12550 2700)(-12550 2600);
WIRE 16 -1 (-12850 2800)(-12550 2800);
WIRE 16 -1 (-12550 2800)(-12550 2700);
WIRE 16 -1 (-5800 3550)(-5800 3700);
WIRE 16 -1 (-6150 3550)(-6150 3700);
WIRE 16 -1 (-5800 3700)(-6150 3700);
WIRE 16 -1 (-12850 2900)(-12550 2900);
WIRE 16 -1 (-12550 2900)(-12550 2800);
WIRE 16 -1 (-12850 3000)(-12550 3000);
WIRE 16 -1 (-12550 2900)(-12550 3000);
WIRE 16 -1 (-6500 3550)(-6500 3700);
WIRE 16 -1 (-6500 3700)(-6150 3700);
WIRE 16 -1 (-6850 3550)(-6850 3700);
WIRE 16 -1 (-6850 3700)(-6500 3700);
WIRE 16 -1 (-12550 3000)(-12550 3200);
WIRE 16 -1 (-12550 3200)(-12850 3200);
WIRE 16 -1 (-12850 3300)(-12550 3300);
WIRE 16 -1 (-12550 3300)(-12550 3200);
WIRE 16 -1 (-7250 3550)(-7250 3700);
WIRE 16 -1 (-7250 3700)(-6850 3700);
WIRE 16 -1 (-7650 3550)(-7650 3700);
WIRE 16 -1 (-7650 3700)(-7250 3700);
WIRE 16 -1 (-12850 3400)(-12550 3400);
WIRE 16 -1 (-12550 3400)(-12550 3300);
WIRE 16 -1 (-12850 3500)(-12550 3500);
WIRE 16 -1 (-12550 3500)(-12550 3400);
WIRE 16 -1 (-8000 3550)(-8000 3700);
WIRE 16 -1 (-8000 3700)(-7650 3700);
WIRE 16 -1 (-8350 3550)(-8350 3700);
WIRE 16 -1 (-8350 3700)(-8000 3700);
WIRE 16 -1 (-12850 3600)(-12550 3600);
WIRE 16 -1 (-12550 3600)(-12550 3500);
WIRE 16 -1 (-12850 5300)(-12550 5300);
WIRE 16 -1 (-12850 3700)(-12550 3700);
WIRE 16 -1 (-12550 3600)(-12550 3700);
WIRE 16 -1 (-8700 3550)(-8700 3700);
WIRE 16 -1 (-8700 3700)(-8350 3700);
WIRE 16 -1 (-9100 3550)(-9100 3700);
WIRE 16 -1 (-9100 3700)(-8700 3700);
WIRE 16 -1 (-12550 3900)(-12850 3900);
WIRE 16 -1 (-12550 3700)(-12550 3900);
WIRE 16 -1 (-12850 5200)(-12550 5200);
WIRE 16 -1 (-12550 5300)(-12550 5200);
WIRE 16 -1 (-12850 5000)(-12550 5000);
WIRE 16 -1 (-12550 5200)(-12550 5000);
WIRE 16 -1 (-12850 4000)(-12550 4000);
WIRE 16 -1 (-12550 4000)(-12550 3900);
WIRE 16 -1 (-9500 3550)(-9500 3700);
WIRE 16 -1 (-9500 3700)(-9100 3700);
WIRE 16 -1 (-9850 3550)(-9850 3700);
WIRE 16 -1 (-9850 3700)(-9500 3700);
WIRE 16 -1 (-12550 4100)(-12550 4000);
WIRE 16 -1 (-12850 4100)(-12550 4100);
WIRE 16 -1 (-12850 4900)(-12550 4900);
WIRE 16 -1 (-12550 5000)(-12550 4900);
WIRE 16 -1 (-12850 4800)(-12550 4800);
WIRE 16 -1 (-12550 4900)(-12550 4800);
WIRE 16 -1 (-12850 4200)(-12550 4200);
WIRE 16 -1 (-12550 4200)(-12550 4100);
WIRE 16 -1 (-10200 3550)(-10200 3700);
WIRE 16 -1 (-10200 3700)(-9850 3700);
WIRE 16 -1 (-10550 3550)(-10550 3700);
WIRE 16 -1 (-10550 3700)(-10200 3700);
WIRE 16 -1 (-12850 4300)(-12550 4300);
WIRE 16 -1 (-12550 4300)(-12550 4200);
WIRE 16 -1 (-12850 4700)(-12550 4700);
WIRE 16 -1 (-12550 4800)(-12550 4700);
WIRE 16 -1 (-12550 4600)(-12850 4600);
WIRE 16 -1 (-12550 4700)(-12550 4600);
WIRE 16 -1 (-12850 4400)(-12550 4400);
WIRE 16 -1 (-12550 4300)(-12550 4400);
WIRE 16 -1 (-10950 3550)(-10950 3700);
WIRE 16 -1 (-10950 3700)(-10550 3700);
WIRE 16 -1 (-11600 3700)(-10950 3700);
WIRE 16 -1 (-12550 4400)(-12550 4550);
WIRE 16 -1 (-12550 4550)(-12550 4600);
WIRE 16 -1 (-12550 4550)(-11600 4550);
WIRE 16 -1 (-11600 4550)(-11600 3700);
WIRE 16 -1 (-10950 4550)(-11600 4550);
WIRE 16 -1 (-10950 4400)(-10950 4550);
WIRE 16 -1 (-10950 4550)(-10550 4550);
WIRE 16 -1 (-10550 4550)(-10550 4400);
WIRE 16 -1 (-10550 4550)(-10200 4550);
WIRE 16 -1 (-10200 4550)(-10200 4400);
WIRE 16 -1 (-10200 4550)(-9800 4550);
WIRE 16 -1 (-9800 4550)(-9800 4400);
WIRE 16 -1 (-9350 4550)(-9800 4550);
WIRE 16 -1 (-9350 4400)(-9350 4550);
WIRE 16 -1 (-9350 4550)(-8950 4550);
WIRE 16 -1 (-8950 4550)(-8950 4400);
WIRE 16 -1 (-8950 4550)(-8600 4550);
WIRE 16 -1 (-8600 4400)(-8600 4550);
WIRE 16 -1 (-8600 4550)(-8250 4550);
WIRE 16 -1 (-8250 4550)(-8250 4400);
WIRE 16 -1 (-8250 4550)(-7900 4550);
WIRE 16 -1 (-7900 4400)(-7900 4550);
WIRE 16 -1 (-7900 4550)(-7500 4550);
WIRE 16 -1 (-7500 4550)(-7500 4400);
WIRE 16 -1 (-7500 4550)(-7150 4550);
WIRE 16 -1 (-7150 4400)(-7150 4550);
WIRE 16 -1 (-7150 4550)(-6750 4550);
WIRE 16 -1 (-6750 4550)(-6750 4400);
WIRE 16 -1 (-6750 4550)(-6400 4550);
WIRE 16 -1 (-6400 4400)(-6400 4550);
WIRE 16 -1 (-6400 4550)(-6050 4550);
WIRE 16 -1 (-6050 4400)(-6050 4550);
WIRE 16 -1 (-6050 4550)(-5700 4550);
WIRE 16 -1 (-5700 4400)(-5700 4550);
WIRE 16 -1 (-5700 4550)(-5350 4550);
WIRE 16 -1 (-5350 4400)(-5350 4550);
WIRE 16 -1 (-5350 4550)(-5000 4550);
WIRE 16 -1 (-5000 4400)(-5000 4550);
WIRE 16 -1 (-4600 4550)(-5000 4550);
WIRE 16 -1 (-4600 4550)(-4600 4400);
WIRE 16 -1 (-4250 4550)(-4600 4550);
WIRE 16 -1 (-14450 8000)(-14150 8000);
WIRE 16 -1 (-14450 8000)(-14450 7900);
WIRE 16 -1 (-14450 7900)(-14150 7900);
WIRE 16 -1 (-14450 7900)(-14450 7800);
WIRE 16 -1 (-14450 7800)(-14150 7800);
WIRE 16 -1 (-14450 7800)(-14450 7700);
WIRE 16 -1 (-14450 7700)(-14150 7700);
WIRE 16 -1 (-14450 7700)(-14450 7600);
WIRE 16 -1 (-14450 7600)(-14150 7600);
WIRE 16 -1 (-14450 7600)(-14450 7500);
WIRE 16 -1 (-14450 7500)(-14150 7500);
WIRE 16 -1 (-14450 7500)(-14450 7400);
WIRE 16 -1 (-14450 7400)(-14150 7400);
WIRE 16 -1 (-14450 7400)(-14450 7300);
WIRE 16 -1 (-14450 7300)(-14150 7300);
WIRE 16 -1 (-14450 7300)(-14450 7200);
WIRE 16 -1 (-14450 7200)(-14150 7200);
WIRE 16 -1 (-14450 7200)(-14450 7100);
WIRE 16 -1 (-14450 7100)(-14150 7100);
WIRE 16 -1 (-14450 7100)(-14450 7000);
WIRE 16 -1 (-14450 7000)(-14150 7000);
WIRE 16 -1 (-14450 7000)(-14450 6900);
WIRE 16 -1 (-14450 6900)(-14150 6900);
WIRE 16 -1 (-14450 6900)(-14450 6800);
WIRE 16 -1 (-14450 6800)(-14150 6800);
WIRE 16 -1 (-14450 6800)(-14450 6700);
WIRE 16 -1 (-14450 6700)(-14150 6700);
WIRE 16 -1 (-14450 6700)(-14450 6600);
WIRE 16 -1 (-14450 6600)(-14150 6600);
WIRE 16 -1 (-14450 6600)(-14450 6500);
WIRE 16 -1 (-14450 6500)(-14150 6500);
WIRE 16 -1 (-14450 6500)(-14450 6400);
WIRE 16 -1 (-14450 6400)(-14150 6400);
WIRE 16 -1 (-14450 6400)(-14450 6300);
WIRE 16 -1 (-14450 6300)(-14150 6300);
WIRE 16 -1 (-14450 6300)(-14450 6200);
WIRE 16 -1 (-14450 6200)(-14150 6200);
WIRE 16 -1 (-14450 6200)(-14450 6100);
WIRE 16 -1 (-14450 6100)(-14150 6100);
WIRE 16 -1 (-14450 6100)(-14450 6000);
WIRE 16 -1 (-14450 6000)(-14150 6000);
WIRE 16 -1 (-14450 6000)(-14450 5900);
WIRE 16 -1 (-14450 5900)(-14150 5900);
WIRE 16 -1 (-14450 5900)(-14450 5800);
WIRE 16 -1 (-14450 5800)(-14150 5800);
WIRE 16 -1 (-14450 5800)(-14450 5700);
WIRE 16 -1 (-14450 5700)(-14150 5700);
WIRE 16 -1 (-14450 5700)(-14450 5600);
WIRE 16 -1 (-14450 5600)(-14150 5600);
WIRE 16 -1 (-14450 5600)(-14450 5500);
WIRE 16 -1 (-14450 5500)(-14150 5500);
WIRE 16 -1 (-14450 5500)(-14450 5400);
WIRE 16 -1 (-14450 5400)(-14150 5400);
WIRE 16 -1 (-14450 5400)(-14450 5300);
WIRE 16 -1 (-14450 5300)(-14150 5300);
WIRE 16 -1 (-14450 5300)(-14450 5200);
WIRE 16 -1 (-14450 5200)(-14150 5200);
WIRE 16 -1 (-14450 5200)(-14450 5100);
WIRE 16 -1 (-14450 5100)(-14150 5100);
WIRE 16 -1 (-14450 5100)(-14450 5000);
WIRE 16 -1 (-14450 5000)(-14150 5000);
WIRE 16 -1 (-14450 5000)(-14450 4900);
WIRE 16 -1 (-14450 4900)(-14150 4900);
WIRE 16 -1 (-14450 4900)(-14450 4800);
WIRE 16 -1 (-14450 4800)(-14150 4800);
WIRE 16 -1 (-14450 4800)(-14450 4700);
WIRE 16 -1 (-14450 4700)(-14150 4700);
WIRE 16 -1 (-14450 4700)(-14450 4600);
WIRE 16 -1 (-14450 4600)(-14150 4600);
WIRE 16 -1 (-14450 4600)(-14450 4500);
WIRE 16 -1 (-14450 4500)(-14150 4500);
WIRE 16 -1 (-14450 4500)(-14450 4400);
WIRE 16 -1 (-14450 4400)(-14150 4400);
WIRE 16 -1 (-14450 4400)(-14450 4300);
WIRE 16 -1 (-14450 4300)(-14150 4300);
WIRE 16 -1 (-14450 4300)(-14450 4200);
WIRE 16 -1 (-14450 4200)(-14150 4200);
WIRE 16 -1 (-14450 4200)(-14450 4100);
WIRE 16 -1 (-14450 4100)(-14150 4100);
WIRE 16 -1 (-14450 4000)(-14150 4000);
WIRE 16 -1 (-14450 4100)(-14450 4000);
WIRE 16 -1 (-14450 4000)(-14450 3900);
WIRE 16 -1 (-14450 3900)(-14150 3900);
WIRE 16 -1 (-14450 3900)(-14450 3800);
WIRE 16 -1 (-14450 3800)(-14150 3800);
WIRE 16 -1 (-14450 3800)(-14450 3700);
WIRE 16 -1 (-14450 3700)(-14150 3700);
WIRE 16 -1 (-14450 3700)(-14450 3600);
WIRE 16 -1 (-14450 3600)(-14150 3600);
WIRE 16 -1 (-14450 3600)(-14450 3500);
WIRE 16 -1 (-14450 3500)(-14150 3500);
WIRE 16 -1 (-14450 3500)(-14450 3400);
WIRE 16 -1 (-14450 3400)(-14150 3400);
WIRE 16 -1 (-14450 3400)(-14450 3300);
WIRE 16 -1 (-14450 3300)(-14150 3300);
WIRE 16 -1 (-14450 3300)(-14450 3200);
WIRE 16 -1 (-14450 3200)(-14150 3200);
WIRE 16 -1 (-14450 3100)(-14450 3200);
WIRE 16 -1 (-14450 3100)(-14150 3100);
WIRE 16 -1 (-14450 3100)(-14450 3000);
WIRE 16 -1 (-14450 3000)(-14150 3000);
WIRE 16 -1 (-14450 3000)(-14450 2900);
WIRE 16 -1 (-14450 2900)(-14150 2900);
WIRE 16 -1 (-14450 2900)(-14450 2800);
WIRE 16 -1 (-14450 2800)(-14150 2800);
WIRE 16 -1 (-14450 2800)(-14450 2700);
WIRE 16 -1 (-14450 2700)(-14150 2700);
WIRE 16 -1 (-14450 2700)(-14450 2600);
WIRE 16 -1 (-14450 2600)(-14150 2600);
WIRE 16 -1 (-14450 2600)(-14450 2500);
WIRE 16 -1 (-14450 2500)(-14150 2500);
WIRE 16 -1 (-14450 2500)(-14450 2400);
WIRE 16 -1 (-14450 2400)(-14150 2400);
WIRE 16 -1 (-14450 2400)(-14450 2300);
WIRE 16 -1 (-14450 2300)(-14150 2300);
WIRE 16 -1 (-14450 2300)(-14450 2200);
WIRE 16 -1 (-14450 2200)(-14150 2200);
WIRE 16 -1 (-14450 2200)(-14450 2100);
WIRE 16 -1 (-14450 2100)(-14150 2100);
WIRE 16 -1 (-14450 2100)(-14450 2000);
WIRE 16 -1 (-14450 2000)(-14150 2000);
WIRE 16 -1 (-14450 2000)(-14450 1900);
WIRE 16 -1 (-14450 1900)(-14150 1900);
WIRE 16 -1 (-14450 1900)(-14450 1800);
WIRE 16 -1 (-14450 1800)(-14150 1800);
WIRE 16 -1 (-14450 1800)(-14450 1700);
WIRE 16 -1 (-14450 1700)(-14150 1700);
WIRE 16 -1 (-14450 1700)(-14450 1600);
WIRE 16 -1 (-14450 1600)(-14150 1600);
WIRE 16 -1 (-14450 1600)(-14450 1500);
WIRE 16 -1 (-14450 1500)(-14150 1500);
WIRE 16 -1 (-14450 1500)(-14450 1400);
WIRE 16 -1 (-14450 1400)(-14150 1400);
WIRE 16 -1 (-14450 1400)(-14450 1300);
WIRE 16 -1 (-14450 1300)(-14150 1300);
WIRE 16 -1 (-14450 1300)(-14450 1200);
WIRE 16 -1 (-14450 1200)(-14150 1200);
WIRE 16 -1 (-14450 1200)(-14450 1100);
WIRE 16 -1 (-14450 1100)(-14150 1100);
WIRE 16 -1 (-14450 1100)(-14450 1000);
WIRE 16 -1 (-14450 1000)(-14150 1000);
WIRE 16 -1 (-14450 1000)(-14450 900);
WIRE 16 -1 (-14450 900)(-14150 900);
WIRE 16 -1 (-14450 900)(-14450 800);
WIRE 16 -1 (-14450 800)(-14150 800);
WIRE 16 -1 (-14450 800)(-14450 700);
WIRE 16 -1 (-14450 700)(-14150 700);
WIRE 16 -1 (-14450 700)(-14450 600);
WIRE 16 -1 (-14450 600)(-14150 600);
WIRE 16 -1 (-14450 600)(-14450 500);
WIRE 16 -1 (-14450 500)(-14150 500);
WIRE 16 -1 (-14450 500)(-14450 400);
WIRE 16 -1 (-14450 400)(-14150 400);
WIRE 16 -1 (-14450 400)(-14450 300);
WIRE 16 -1 (-14450 300)(-14150 300);
WIRE 16 -1 (-14450 300)(-14450 200);
WIRE 16 -1 (-14450 200)(-14150 200);
WIRE 16 -1 (-14450 200)(-14450 100);
WIRE 16 -1 (-14450 100)(-14150 100);
WIRE 16 -1 (-14450 100)(-14450 0);
WIRE 16 -1 (-14450 0)(-14150 0);
WIRE 16 -1 (-14450 -100)(-14150 -100);
WIRE 16 -1 (-14450 -100)(-14450 0);
WIRE 16 -1 (-14450 -100)(-14450 -200);
WIRE 16 -1 (-14450 -200)(-14150 -200);
WIRE 16 -1 (-14450 -200)(-14450 -300);
WIRE 16 -1 (-14450 -300)(-14150 -300);
WIRE 16 -1 (-14450 -300)(-14450 -400);
WIRE 16 -1 (-14450 -400)(-14150 -400);
WIRE 16 -1 (-14450 -400)(-14450 -500);
WIRE 16 -1 (-14450 -500)(-14150 -500);
WIRE 16 -1 (-14450 -500)(-14450 -600);
WIRE 16 -1 (-14450 -600)(-14150 -600);
WIRE 16 -1 (-12850 100)(-12550 100);
WIRE 16 -1 (-12550 0)(-12550 100);
WIRE 16 -1 (-12850 0)(-12550 0);
WIRE 16 -1 (-12850 -100)(-12550 -100);
WIRE 16 -1 (-12550 -100)(-12550 0);
WIRE 16 -1 (-12850 -200)(-12550 -200);
WIRE 16 -1 (-12550 -200)(-12550 -100);
WIRE 16 -1 (-12850 -300)(-12550 -300);
WIRE 16 -1 (-12550 -300)(-12550 -200);
WIRE 16 -1 (-12550 -400)(-12850 -400);
WIRE 16 -1 (-12550 -400)(-12550 -300);
WIRE 16 -1 (-12550 -400)(-11200 -400);
WIRE 16 -1 (-10950 -400)(-11200 -400);
WIRE 16 -1 (-10950 -550)(-10950 -400);
WIRE 16 -1 (-10950 -400)(-10600 -400);
WIRE 16 -1 (-10600 -550)(-10600 -400);
WIRE 16 -1 (-10600 -400)(-10200 -400);
WIRE 16 -1 (-10200 -550)(-10200 -400);
WIRE 16 -1 (-9800 -400)(-10200 -400);
WIRE 16 -1 (-9800 -550)(-9800 -400);
WIRE 16 -1 (-9800 -400)(-9450 -400);
WIRE 16 -1 (-9450 -550)(-9450 -400);
WIRE 16 -1 (-9450 -400)(-9100 -400);
WIRE 16 -1 (-9100 -550)(-9100 -400);
WIRE 16 -1 (-8650 -400)(-9100 -400);
WIRE 16 -1 (-8500 -400)(-8650 -400);
WIRE 16 -1 (-8650 -550)(-8650 -400);
WIRE 16 -1 (-5800 3300)(-5800 3200);
WIRE 16 -1 (-6150 3300)(-6150 3200);
WIRE 16 -1 (-5800 3200)(-6150 3200);
WIRE 16 -1 (-6500 3300)(-6500 3200);
WIRE 16 -1 (-6500 3200)(-6150 3200);
WIRE 16 -1 (-6850 3300)(-6850 3200);
WIRE 16 -1 (-6850 3200)(-6500 3200);
WIRE 16 -1 (-7250 3200)(-7250 3300);
WIRE 16 -1 (-7250 3200)(-6850 3200);
WIRE 16 -1 (-7650 3200)(-7650 3300);
WIRE 16 -1 (-7650 3200)(-7250 3200);
WIRE 16 -1 (-8000 3300)(-8000 3200);
WIRE 16 -1 (-7650 3200)(-8000 3200);
WIRE 16 -1 (-8350 3200)(-8350 3300);
WIRE 16 -1 (-8000 3200)(-8350 3200);
WIRE 16 -1 (-8700 3300)(-8700 3200);
WIRE 16 -1 (-8700 3200)(-8350 3200);
WIRE 16 -1 (-9100 3300)(-9100 3200);
WIRE 16 -1 (-9100 3200)(-8700 3200);
WIRE 16 -1 (-9500 3300)(-9500 3200);
WIRE 16 -1 (-9500 3200)(-9100 3200);
WIRE 16 -1 (-9850 3300)(-9850 3200);
WIRE 16 -1 (-9850 3200)(-9500 3200);
WIRE 16 -1 (-10200 3300)(-10200 3200);
WIRE 16 -1 (-9850 3200)(-10200 3200);
WIRE 16 -1 (-10550 3300)(-10550 3200);
WIRE 16 -1 (-10200 3200)(-10550 3200);
WIRE 16 -1 (-10950 3200)(-10950 3300);
WIRE 16 -1 (-10950 3200)(-10550 3200);
WIRE 16 -1 (-7550 -800)(-7550 -950);
WIRE 16 -1 (-8000 -800)(-8000 -950);
WIRE 16 -1 (-8000 -950)(-7550 -950);
WIRE 16 -1 (-8650 -800)(-8650 -950);
WIRE 16 -1 (-8000 -950)(-8650 -950);
WIRE 16 -1 (-9100 -800)(-9100 -950);
WIRE 16 -1 (-8650 -950)(-9100 -950);
WIRE 16 -1 (-9450 -950)(-9450 -800);
WIRE 16 -1 (-9450 -950)(-9100 -950);
WIRE 16 -1 (-9800 -950)(-9800 -800);
WIRE 16 -1 (-9800 -950)(-9450 -950);
WIRE 16 -1 (-10200 -800)(-10200 -950);
WIRE 16 -1 (-10200 -950)(-9800 -950);
WIRE 16 -1 (-10600 -800)(-10600 -950);
WIRE 16 -1 (-10600 -950)(-10200 -950);
WIRE 16 -1 (-7950 550)(-7950 700);
WIRE 16 -1 (-7950 700)(-7750 700);
WIRE 16 -1 (-8350 550)(-8350 700);
WIRE 16 -1 (-8350 700)(-7950 700);
WIRE 16 -1 (-8700 550)(-8700 700);
WIRE 16 -1 (-8700 700)(-8350 700);
WIRE 16 -1 (-9050 550)(-9050 700);
WIRE 16 -1 (-8700 700)(-9050 700);
WIRE 16 -1 (-9400 550)(-9400 700);
WIRE 16 -1 (-9050 700)(-9400 700);
WIRE 16 -1 (-9750 550)(-9750 700);
WIRE 16 -1 (-9400 700)(-9750 700);
WIRE 16 -1 (-10150 550)(-10150 700);
WIRE 16 -1 (-9750 700)(-10150 700);
WIRE 16 -1 (-12550 700)(-12850 700);
WIRE 16 -1 (-12550 700)(-10150 700);
FORCEPROP 2 LAST SIG_NAME XP1R0V_FPGA_MGTAVCC
J 0
(-11910 710);
DISPLAY 1.021277 (-11910 710);
WIRE 16 -1 (-12550 600)(-12550 700);
WIRE 16 -1 (-12850 600)(-12550 600);
WIRE 16 -1 (-12550 500)(-12550 600);
WIRE 16 -1 (-12850 500)(-12550 500);
WIRE 16 -1 (-12550 400)(-12550 500);
WIRE 16 -1 (-12850 400)(-12550 400);
WIRE 16 -1 (-12550 300)(-12550 400);
WIRE 16 -1 (-12850 300)(-12550 300);
WIRE 16 -1 (-3600 5800)(-3600 5950);
WIRE 16 -1 (-3450 5950)(-3600 5950);
WIRE 16 -1 (-3950 5800)(-3950 5950);
WIRE 16 -1 (-3950 5950)(-3600 5950);
WIRE 16 -1 (-4300 5950)(-4300 5800);
WIRE 16 -1 (-4300 5950)(-3950 5950);
WIRE 16 -1 (-4650 5800)(-4650 5950);
WIRE 16 -1 (-4300 5950)(-4650 5950);
WIRE 16 -1 (-5000 5950)(-5000 5800);
WIRE 16 -1 (-4650 5950)(-5000 5950);
WIRE 16 -1 (-5400 5950)(-5400 5800);
WIRE 16 -1 (-5000 5950)(-5400 5950);
WIRE 16 -1 (-5750 5950)(-5750 5800);
WIRE 16 -1 (-5400 5950)(-5750 5950);
WIRE 16 -1 (-6150 5800)(-6150 5950);
WIRE 16 -1 (-5750 5950)(-6150 5950);
WIRE 16 -1 (-6500 5800)(-6500 5950);
WIRE 16 -1 (-6150 5950)(-6500 5950);
WIRE 16 -1 (-6850 5800)(-6850 5950);
WIRE 16 -1 (-6850 5950)(-6500 5950);
WIRE 16 -1 (-7200 5800)(-7200 5950);
WIRE 16 -1 (-7200 5950)(-6850 5950);
WIRE 16 -1 (-7600 5800)(-7600 5950);
WIRE 16 -1 (-7600 5950)(-7200 5950);
WIRE 16 -1 (-8000 5800)(-8000 5950);
WIRE 16 -1 (-8000 5950)(-7600 5950);
WIRE 16 -1 (-8350 5800)(-8350 5950);
WIRE 16 -1 (-8350 5950)(-8000 5950);
WIRE 16 -1 (-8750 5800)(-8750 5950);
WIRE 16 -1 (-8750 5950)(-8350 5950);
WIRE 16 -1 (-9100 5800)(-9100 5950);
WIRE 16 -1 (-9100 5950)(-8750 5950);
WIRE 16 -1 (-12550 5500)(-12850 5500);
WIRE 16 -1 (-9450 5800)(-9450 5950);
WIRE 16 -1 (-9450 5950)(-9100 5950);
WIRE 16 -1 (-9800 5800)(-9800 5950);
WIRE 16 -1 (-9800 5950)(-9450 5950);
WIRE 16 -1 (-12850 5600)(-12550 5600);
WIRE 16 -1 (-12550 5600)(-12550 5500);
WIRE 16 -1 (-12850 5700)(-12550 5700);
WIRE 16 -1 (-12550 5700)(-12550 5600);
WIRE 16 -1 (-10200 5800)(-10200 5950);
WIRE 16 -1 (-10200 5950)(-9800 5950);
WIRE 16 -1 (-10600 5800)(-10600 5950);
WIRE 16 -1 (-10600 5950)(-10200 5950);
WIRE 16 -1 (-12850 5800)(-12550 5800);
WIRE 16 -1 (-12550 5800)(-12550 5700);
WIRE 16 -1 (-12850 5900)(-12550 5900);
WIRE 16 -1 (-12550 5900)(-12550 5800);
WIRE 16 -1 (-10950 5800)(-10950 5950);
WIRE 16 -1 (-10950 5950)(-10600 5950);
WIRE 16 -1 (-10950 5950)(-12550 5950);
FORCEPROP 2 LAST SIG_NAME XP1R0V_FPGA_VCCINT
J 0
(-12210 5960);
DISPLAY 1.021277 (-12210 5960);
WIRE 16 -1 (-12550 5950)(-12550 5900);
WIRE 16 -1 (-12550 5950)(-12550 6000);
WIRE 16 -1 (-12850 6000)(-12550 6000);
WIRE 16 -1 (-12550 6100)(-12850 6100);
WIRE 16 -1 (-12550 6100)(-12550 6000);
WIRE 16 -1 (-12550 6200)(-12550 6100);
WIRE 16 -1 (-12850 6200)(-12550 6200);
WIRE 16 -1 (-12550 6300)(-12550 6200);
WIRE 16 -1 (-12850 6300)(-12550 6300);
WIRE 16 -1 (-12550 6400)(-12550 6300);
WIRE 16 -1 (-12850 6400)(-12550 6400);
WIRE 16 -1 (-12550 6500)(-12550 6400);
WIRE 16 -1 (-12850 6500)(-12550 6500);
WIRE 16 -1 (-12550 6500)(-12550 6600);
WIRE 16 -1 (-12850 6600)(-12550 6600);
WIRE 16 -1 (-12550 6700)(-12850 6700);
WIRE 16 -1 (-12550 6700)(-12550 6600);
WIRE 16 -1 (-12550 6800)(-12550 6700);
WIRE 16 -1 (-12850 6800)(-12550 6800);
WIRE 16 -1 (-12550 7000)(-12550 6800);
WIRE 16 -1 (-12850 7000)(-12550 7000);
WIRE 16 -1 (-12550 7100)(-12550 7000);
WIRE 16 -1 (-12850 7100)(-12550 7100);
WIRE 16 -1 (-12550 7200)(-12550 7100);
WIRE 16 -1 (-12850 7200)(-12550 7200);
WIRE 16 -1 (-7900 7250)(-7900 7400);
WIRE 16 -1 (-7600 7400)(-7900 7400);
WIRE 16 -1 (-8350 7400)(-8350 7250);
WIRE 16 -1 (-8350 7400)(-7900 7400);
WIRE 16 -1 (-8750 7400)(-8750 7250);
WIRE 16 -1 (-8750 7400)(-8350 7400);
WIRE 16 -1 (-9100 7400)(-9100 7250);
WIRE 16 -1 (-9100 7400)(-8750 7400);
WIRE 16 -1 (-9500 7250)(-9500 7400);
WIRE 16 -1 (-9500 7400)(-9100 7400);
WIRE 16 -1 (-9900 7250)(-9900 7400);
WIRE 16 -1 (-9900 7400)(-9500 7400);
WIRE 16 -1 (-10250 7250)(-10250 7400);
WIRE 16 -1 (-10250 7400)(-9900 7400);
WIRE 16 -1 (-10600 7250)(-10600 7400);
WIRE 16 -1 (-10600 7400)(-10250 7400);
WIRE 16 -1 (-12850 7300)(-12550 7300);
WIRE 16 -1 (-10950 7250)(-10950 7400);
WIRE 16 -1 (-10950 7400)(-10600 7400);
WIRE 16 -1 (-12550 7400)(-10950 7400);
FORCEPROP 2 LAST SIG_NAME XP1R8V_FPGA_VCCAUX
J 0
(-12260 7410);
DISPLAY 1.021277 (-12260 7410);
WIRE 16 -1 (-12550 7400)(-12550 7300);
WIRE 16 -1 (-12550 7500)(-12850 7500);
WIRE 16 -1 (-12550 7500)(-12550 7400);
WIRE 16 -1 (-12550 7600)(-12550 7500);
WIRE 16 -1 (-12850 7600)(-12550 7600);
WIRE 16 -1 (-12550 7700)(-12550 7600);
WIRE 16 -1 (-12850 7700)(-12550 7700);
WIRE 16 -1 (-12550 7800)(-12550 7700);
WIRE 16 -1 (-12850 7800)(-12550 7800);
WIRE 16 -1 (-12550 7900)(-12550 7800);
WIRE 16 -1 (-12850 7900)(-12550 7900);
WIRE 16 -1 (-12550 8000)(-12550 7900);
WIRE 16 -1 (-12850 8000)(-12550 8000);
DOT 1 (-5000 4550);
DOT 1 (-6750 700);
DOT 1 (-3950 5450);
DOT 1 (-8650 -400);
DOT 1 (-9450 -400);
DOT 1 (-8650 -950);
DOT 1 (-8400 2300);
DOT 1 (-10950 1800);
DOT 1 (-8600 4550);
DOT 1 (-8700 3200);
DOT 1 (-9100 3200);
DOT 1 (-6500 3700);
DOT 1 (-7650 3700);
DOT 1 (-7650 3200);
DOT 1 (-6850 5950);
DOT 1 (-2400 5950);
DOT 1 (-9050 150);
DOT 1 (-5400 5450);
DOT 1 (-5700 4050);
DOT 1 (-9750 700);
DOT 1 (-5750 5450);
DOT 1 (-5350 4050);
DOT 1 (-9800 4050);
DOT 1 (-7600 1800);
DOT 1 (-6150 3700);
DOT 1 (-12550 4600);
DOT 1 (-8250 4050);
DOT 1 (-6850 3700);
DOT 1 (-14450 6500);
DOT 1 (-6750 4550);
DOT 1 (-4600 4550);
DOT 1 (-5000 4050);
DOT 1 (-5350 4550);
DOT 1 (-12550 4800);
DOT 1 (-12550 2700);
DOT 1 (-14450 4700);
DOT 1 (-6400 4050);
DOT 1 (-9900 6900);
DOT 1 (-7950 700);
DOT 1 (-9100 -400);
DOT 1 (-12550 700);
DOT 1 (-10150 700);
DOT 1 (-9800 -400);
DOT 1 (-12550 3700);
DOT 1 (-14450 4000);
DOT 1 (-7900 6900);
DOT 1 (-7500 4550);
DOT 1 (-7250 1800);
DOT 1 (-12550 1500);
DOT 1 (-12550 1800);
DOT 1 (-10200 3200);
DOT 1 (-12550 4900);
DOT 1 (-12550 4550);
DOT 1 (-6750 4050);
DOT 1 (-5700 4550);
DOT 1 (-6050 4050);
DOT 1 (-6050 4550);
DOT 1 (-6400 4550);
DOT 1 (-6500 5450);
DOT 1 (-6500 3200);
DOT 1 (-6900 1800);
DOT 1 (-9450 -950);
DOT 1 (-7250 3200);
DOT 1 (-9400 150);
DOT 1 (-12550 3000);
DOT 1 (-8000 3700);
DOT 1 (-8950 4050);
DOT 1 (-8350 6900);
DOT 1 (-10600 5450);
DOT 1 (-10950 4550);
DOT 1 (-9100 -950);
DOT 1 (-10200 4050);
DOT 1 (-10550 4550);
DOT 1 (-9350 4550);
DOT 1 (-6500 5950);
DOT 1 (-8750 6900);
DOT 1 (-5750 5950);
DOT 1 (-9800 4550);
DOT 1 (-9100 5450);
DOT 1 (-6150 3200);
DOT 1 (-7250 3700);
DOT 1 (-6900 7400);
DOT 1 (-6400 7400);
DOT 1 (-6900 6900);
DOT 1 (-7900 7400);
DOT 1 (-10200 3700);
DOT 1 (-5400 5950);
DOT 1 (-6150 5950);
DOT 1 (-7200 5950);
DOT 1 (-7600 5950);
DOT 1 (-8000 5950);
DOT 1 (-8350 5950);
DOT 1 (-8750 5950);
DOT 1 (-9100 5950);
DOT 1 (-9450 5950);
DOT 1 (-9800 5950);
DOT 1 (-10200 5950);
DOT 1 (-14450 6200);
DOT 1 (-9100 3700);
DOT 1 (-11600 4550);
DOT 1 (-12550 7000);
DOT 1 (-9450 5450);
DOT 1 (-10550 4050);
DOT 1 (-10200 4550);
DOT 1 (-10950 3200);
DOT 1 (-10950 3700);
DOT 1 (-10550 3200);
DOT 1 (-10550 3700);
DOT 1 (-9850 3700);
DOT 1 (-9500 3700);
DOT 1 (-8700 3700);
DOT 1 (-8350 3700);
DOT 1 (-8000 3200);
DOT 1 (-10950 5450);
DOT 1 (-10950 5950);
DOT 1 (-10950 6900);
DOT 1 (-10600 6900);
DOT 1 (-10950 7400);
DOT 1 (-10600 7400);
DOT 1 (-10200 5450);
DOT 1 (-8750 5450);
DOT 1 (-10250 6900);
DOT 1 (-10250 7400);
DOT 1 (-9900 7400);
DOT 1 (-9500 6900);
DOT 1 (-9100 6900);
DOT 1 (-9500 7400);
DOT 1 (-9100 7400);
DOT 1 (-8750 7400);
DOT 1 (-8350 5450);
DOT 1 (-8000 5450);
DOT 1 (-7600 5450);
DOT 1 (-7200 5450);
DOT 1 (-8350 7400);
DOT 1 (-6150 5450);
DOT 1 (-12550 6100);
DOT 1 (-12550 5900);
DOT 1 (-14450 -800);
DOT 1 (-14450 -500);
DOT 1 (-14450 -600);
DOT 1 (-14450 -400);
DOT 1 (-14450 -300);
DOT 1 (-12550 -200);
DOT 1 (-12550 -300);
DOT 1 (-14450 0);
DOT 1 (-14450 -100);
DOT 1 (-14450 100);
DOT 1 (-14450 300);
DOT 1 (-14450 200);
DOT 1 (-14450 500);
DOT 1 (-14450 400);
DOT 1 (-14450 600);
DOT 1 (-14450 700);
DOT 1 (-14450 800);
DOT 1 (-14450 900);
DOT 1 (-14450 1000);
DOT 1 (-14450 1200);
DOT 1 (-14450 1100);
DOT 1 (-14450 1300);
DOT 1 (-14450 1500);
DOT 1 (-14450 1400);
DOT 1 (-14450 1700);
DOT 1 (-14450 1800);
DOT 1 (-14450 1900);
DOT 1 (-14450 2100);
DOT 1 (-14450 2000);
DOT 1 (-14450 2300);
DOT 1 (-14450 2200);
DOT 1 (-14450 2400);
DOT 1 (-14450 2500);
DOT 1 (-14450 2600);
DOT 1 (-14450 2800);
DOT 1 (-14450 2700);
DOT 1 (-14450 3000);
DOT 1 (-14450 2900);
DOT 1 (-14450 3100);
DOT 1 (-14450 3200);
DOT 1 (-14450 3300);
DOT 1 (-14450 3500);
DOT 1 (-14450 3400);
DOT 1 (-14450 3600);
DOT 1 (-14450 3700);
DOT 1 (-14450 3800);
DOT 1 (-14450 3900);
DOT 1 (-14450 4100);
DOT 1 (-14450 4200);
DOT 1 (-14450 4400);
DOT 1 (-14450 4300);
DOT 1 (-14450 4600);
DOT 1 (-14450 4500);
DOT 1 (-14450 4800);
DOT 1 (-14450 4900);
DOT 1 (-14450 5100);
DOT 1 (-14450 5000);
DOT 1 (-14450 5300);
DOT 1 (-14450 5200);
DOT 1 (-14450 5400);
DOT 1 (-14450 5600);
DOT 1 (-14450 5500);
DOT 1 (-14450 5700);
DOT 1 (-14450 5800);
DOT 1 (-14450 5900);
DOT 1 (-14450 6100);
DOT 1 (-14450 6000);
DOT 1 (-14450 6400);
DOT 1 (-14450 6300);
DOT 1 (-14450 6700);
DOT 1 (-14450 6600);
DOT 1 (-14450 6900);
DOT 1 (-14450 7000);
DOT 1 (-14450 7100);
DOT 1 (-14450 7200);
DOT 1 (-14450 7300);
DOT 1 (-14450 7400);
DOT 1 (-14450 7500);
DOT 1 (-14450 7700);
DOT 1 (-14450 7800);
DOT 1 (-14450 7900);
DOT 1 (-12550 0);
DOT 1 (-12550 -100);
DOT 1 (-12550 500);
DOT 1 (-12550 400);
DOT 1 (-12550 600);
DOT 1 (-12550 1200);
DOT 1 (-12550 1300);
DOT 1 (-12550 1600);
DOT 1 (-12550 2000);
DOT 1 (-12550 3300);
DOT 1 (-12550 3600);
DOT 1 (-12550 3900);
DOT 1 (-12550 4000);
DOT 1 (-12550 4100);
DOT 1 (-12550 4700);
DOT 1 (-12550 5700);
DOT 1 (-12550 5800);
DOT 1 (-12550 5950);
DOT 1 (-12550 6000);
DOT 1 (-12550 6300);
DOT 1 (-12550 6400);
DOT 1 (-12550 6700);
DOT 1 (-12550 6600);
DOT 1 (-12550 6800);
DOT 1 (-12550 7100);
DOT 1 (-12550 7400);
DOT 1 (-12550 7600);
DOT 1 (-12550 7500);
DOT 1 (-12550 7700);
DOT 1 (-12550 7800);
DOT 1 (-12550 7900);
DOT 1 (-12550 1900);
DOT 1 (-12550 3500);
DOT 1 (-12550 4200);
DOT 1 (-14450 -200);
DOT 1 (-8350 3200);
DOT 1 (-14450 1600);
DOT 1 (-12550 2100);
DOT 1 (-12550 2200);
DOT 1 (-12550 2300);
DOT 1 (-12550 -400);
DOT 1 (-10200 -400);
DOT 1 (-10600 -400);
DOT 1 (-10950 -400);
DOT 1 (-9800 -950);
DOT 1 (-10200 -950);
DOT 1 (-10950 -950);
DOT 1 (-8350 700);
DOT 1 (-8700 700);
DOT 1 (-9050 700);
DOT 1 (-9400 700);
DOT 1 (-7250 2300);
DOT 1 (-7600 2300);
DOT 1 (-8000 1800);
DOT 1 (-8750 2300);
DOT 1 (-9100 2300);
DOT 1 (-9100 1800);
DOT 1 (-9500 2300);
DOT 1 (-9500 1800);
DOT 1 (-9900 2300);
DOT 1 (-10250 2300);
DOT 1 (-10600 2300);
DOT 1 (-10950 2300);
DOT 1 (-8250 4550);
DOT 1 (-8950 4550);
DOT 1 (-7150 4050);
DOT 1 (-7500 4050);
DOT 1 (-8600 4050);
DOT 1 (-12550 5200);
DOT 1 (-9350 4050);
DOT 1 (-12550 2900);
DOT 1 (-12550 4400);
DOT 1 (-9500 3200);
DOT 1 (-9900 1800);
DOT 1 (-9800 5450);
DOT 1 (-8350 150);
DOT 1 (-12550 4300);
DOT 1 (-10250 1800);
DOT 1 (-7900 4550);
DOT 1 (-10600 5950);
DOT 1 (-12550 5600);
DOT 1 (-12550 6200);
DOT 1 (-5000 5950);
DOT 1 (-5000 5450);
DOT 1 (-6850 3200);
DOT 1 (-9850 3200);
DOT 1 (-12550 5000);
DOT 1 (-12550 3400);
DOT 1 (-12550 3200);
DOT 1 (-10150 150);
DOT 1 (-10600 -950);
DOT 1 (-7150 4550);
DOT 1 (-12550 6500);
DOT 1 (-6900 2300);
DOT 1 (-10950 4050);
DOT 1 (-7900 4050);
DOT 1 (-3600 5950);
DOT 1 (-3950 5950);
DOT 1 (-4300 5950);
DOT 1 (-3600 5450);
DOT 1 (-4300 5450);
DOT 1 (-2950 5450);
DOT 1 (-4650 5950);
DOT 1 (-4650 5450);
DOT 1 (-14450 6800);
DOT 1 (-12550 2800);
DOT 1 (-10600 1800);
DOT 1 (-2950 5950);
DOT 1 (-6850 5450);
DOT 1 (-8700 150);
DOT 1 (-9750 150);
DOT 1 (-7550 -400);
DOT 1 (-8000 -400);
DOT 1 (-8000 -950);
DOT 1 (-7200 700);
DOT 1 (-7200 150);
DOT 1 (-11200 -400);
DOT 1 (-12550 2600);
DOT 1 (-12550 1400);
DOT 1 (-14450 7600);
DOT 1 (-8400 1800);
DOT 1 (-8750 1800);
DOT 1 (-4600 2300);
DOT 1 (-4950 2300);
DOT 1 (-5350 2300);
DOT 1 (-5700 2300);
DOT 1 (-4950 1800);
DOT 1 (-5350 1800);
DOT 1 (-5700 1800);
DOT 1 (-6450 2300);
DOT 1 (-6450 1800);
DOT 1 (-8000 2300);
DOT 1 (-6050 2300);
DOT 1 (-6050 1800);
DOT 1 (-7950 150);
FORCENOTE
FPGA 5/5
(-9000 8350) 0;
DISPLAY LEFT (-9000 8350);
DISPLAY 3.936170 (-9000 8350);
QUIT
